FILE_TYPE = MACRO_DRAWING;
SET COLOR_WIRE YELLOW;
SET COLOR_PROP ORANGE;
SET COLOR_DOT WHITE;
SET COLOR_ARC YELLOW;
SET COLOR_BODY GREEN;
SET COLOR_NOTE PURPLE;
SET PROP_DISPLAY VALUE;
SET PAGE_NUMBER P31;
SET PATH_NUMBER P81;
FORCEADD OFFPAGE..1
(-7200 4400);
FORCEPROP 2 LAST $XR0 30 
J 0
(-7421 4400);
DISPLAY 0.638298 (-7421 4400);
PAINT MONO (-7421 4400);
FORCEPROP 2 LAST CDS_LIB standard
J 0
(-7200 4400);
DISPLAY INVISIBLE (-7200 4400);
FORCEPROP 1 LAST COMMENT_BODY TRUE
J 0
(-7070 4300);
DISPLAY 1.106383 (-7070 4300);
PAINT PEACH (-7070 4300);
DISPLAY INVISIBLE (-7070 4300);
FORCEPROP 1 LAST OFFPAGE TRUE
J 0
(-6870 4270);
PAINT GREEN (-6870 4270);
DISPLAY INVISIBLE (-6870 4270);
FORCEPROP 2 LAST PATH I1
J 0
(-7450 4450);
DISPLAY 0.680851 (-7450 4450);
DISPLAY INVISIBLE (-7450 4450);
FORCEADD UNIVERSAL_GND..1
R 2
(-4150 4625);
FORCEPROP 3 LASTPIN (-4150 4675) SIG_NAME GND\g
J 0
(-4140 4685);
DISPLAY 0.659574 (-4140 4685);
PAINT MONO (-4140 4685);
DISPLAY INVISIBLE (-4140 4685);
FORCEPROP 2 LAST CDS_LIB logical_power
J 0
(-4150 4625);
DISPLAY INVISIBLE (-4150 4625);
FORCEPROP 1 LAST HDL_POWER GND
J 1
(-4175 4550);
DISPLAY 0.702128 (-4175 4550);
PAINT GREEN (-4175 4550);
DISPLAY INVISIBLE (-4175 4550);
FORCEPROP 1 LAST PATH I10
J 2
(-4225 4625);
DISPLAY 0.872340 (-4225 4625);
PAINT AQUA (-4225 4625);
DISPLAY INVISIBLE (-4225 4625);
FORCEADD Q_CAP..1
R 2
(-4150 4825);
FORCEPROP 1 LAST VOLTAGE 25V
J 2
(-4200 4825);
DISPLAY 0.510638 (-4200 4825);
PAINT SKYBLUE (-4200 4825);
FORCEPROP 1 LAST PACK_TYPE 0402
J 2
(-4200 4625);
DISPLAY 0.510638 (-4200 4625);
PAINT SKYBLUE (-4200 4625);
FORCEPROP 1 LAST MATERIAL X7R
J 2
(-4200 4725);
DISPLAY 0.510638 (-4200 4725);
PAINT SKYBLUE (-4200 4725);
FORCEPROP 1 LAST TOLERANCE 10%
J 2
(-4200 4775);
DISPLAY 0.510638 (-4200 4775);
PAINT SKYBLUE (-4200 4775);
FORCEPROP 1 LAST PART_NUMBER CH4104K1B00
J 2
(-4200 4675);
DISPLAY 0.510638 (-4200 4675);
PAINT WHITE (-4200 4675);
FORCEPROP 1 LAST VALUE 0.1UF
J 2
(-4225 4875);
DISPLAY 0.510638 (-4225 4875);
PAINT SKYBLUE (-4225 4875);
FORCEPROP 2 LAST CDS_LIB pure_quanta
J 0
(-4150 4825);
DISPLAY INVISIBLE (-4150 4825);
FORCEPROP 1 LAST PATH I11
J 2
(-4200 4975);
DISPLAY 0.978723 (-4200 4975);
PAINT WHITE (-4200 4975);
DISPLAY INVISIBLE (-4200 4975);
FORCEPROP 1 LAST LOCATION C501
J 2
(-4200 4925);
DISPLAY 0.702128 (-4200 4925);
PAINT YELLOW (-4200 4925);
FORCEPROP 1 LASTPIN (-4150 4925) $PN 1
J 2
(-4160 4905);
DISPLAY 0.787234 (-4160 4905);
PAINT MONO (-4160 4905);
FORCEPROP 1 LASTPIN (-4150 4725) $PN 2
J 2
(-4160 4705);
DISPLAY 0.787234 (-4160 4705);
PAINT MONO (-4160 4705);
FORCEPROP 0 LAST $SEC 1
J 0
(-4200 4975);
DISPLAY 0.680851 (-4200 4975);
PAINT MONO (-4200 4975);
DISPLAY INVISIBLE (-4200 4975);
FORCEPROP 0 LAST CDS_SEC 1
J 0
(-4200 4975);
DISPLAY 0.680851 (-4200 4975);
DISPLAY INVISIBLE (-4200 4975);
FORCEADD UNIVERSAL_POWER..1
(-4150 5100);
FORCEPROP 3 LASTPIN (-4150 5050) SIG_NAME P3V3_AUX\g
J 0
(-4140 5060);
DISPLAY 0.659574 (-4140 5060);
PAINT MONO (-4140 5060);
DISPLAY INVISIBLE (-4140 5060);
FORCEPROP 1 LAST HDL_POWER P3V3_AUX
J 1
(-4150 5150);
DISPLAY 0.702128 (-4150 5150);
PAINT PEACH (-4150 5150);
FORCEPROP 2 LAST CDS_LIB logical_power
J 0
(-4150 5100);
DISPLAY INVISIBLE (-4150 5100);
FORCEPROP 1 LAST PATH I12
J 0
(-4100 5125);
DISPLAY 0.872340 (-4100 5125);
PAINT AQUA (-4100 5125);
DISPLAY INVISIBLE (-4100 5125);
FORCEADD UNIVERSAL_GND..1
R 2
(-4125 5825);
FORCEPROP 3 LASTPIN (-4125 5875) SIG_NAME GND\g
J 0
(-4115 5885);
DISPLAY 0.659574 (-4115 5885);
PAINT MONO (-4115 5885);
DISPLAY INVISIBLE (-4115 5885);
FORCEPROP 2 LAST CDS_LIB logical_power
J 0
(-4125 5825);
DISPLAY INVISIBLE (-4125 5825);
FORCEPROP 1 LAST HDL_POWER GND
J 1
(-4150 5750);
DISPLAY 0.702128 (-4150 5750);
PAINT GREEN (-4150 5750);
DISPLAY INVISIBLE (-4150 5750);
FORCEPROP 1 LAST PATH I16
J 2
(-4200 5825);
DISPLAY 0.872340 (-4200 5825);
PAINT AQUA (-4200 5825);
DISPLAY INVISIBLE (-4200 5825);
FORCEADD Q_CAP..1
R 2
(-4125 6025);
FORCEPROP 1 LAST TOLERANCE 10%
J 2
(-4175 5975);
DISPLAY 0.510638 (-4175 5975);
PAINT SKYBLUE (-4175 5975);
FORCEPROP 1 LAST VOLTAGE 25V
J 2
(-4175 6025);
DISPLAY 0.510638 (-4175 6025);
PAINT SKYBLUE (-4175 6025);
FORCEPROP 1 LAST MATERIAL X7R
J 2
(-4175 5925);
DISPLAY 0.510638 (-4175 5925);
PAINT SKYBLUE (-4175 5925);
FORCEPROP 1 LAST VALUE 0.1UF
J 2
(-4200 6075);
DISPLAY 0.510638 (-4200 6075);
PAINT SKYBLUE (-4200 6075);
FORCEPROP 1 LAST PART_NUMBER CH4104K1B00
J 2
(-4175 5875);
DISPLAY 0.510638 (-4175 5875);
PAINT WHITE (-4175 5875);
FORCEPROP 1 LAST PACK_TYPE 0402
J 2
(-4175 5825);
DISPLAY 0.510638 (-4175 5825);
PAINT SKYBLUE (-4175 5825);
FORCEPROP 2 LAST CDS_LIB pure_quanta
J 0
(-4125 6025);
DISPLAY INVISIBLE (-4125 6025);
FORCEPROP 1 LAST PATH I17
J 2
(-4175 6175);
DISPLAY 0.978723 (-4175 6175);
PAINT WHITE (-4175 6175);
DISPLAY INVISIBLE (-4175 6175);
FORCEPROP 1 LAST LOCATION C500
J 2
(-4175 6125);
DISPLAY 0.702128 (-4175 6125);
PAINT YELLOW (-4175 6125);
FORCEPROP 1 LASTPIN (-4125 6125) $PN 1
J 2
(-4135 6105);
DISPLAY 0.787234 (-4135 6105);
PAINT MONO (-4135 6105);
FORCEPROP 1 LASTPIN (-4125 5925) $PN 2
J 2
(-4135 5905);
DISPLAY 0.787234 (-4135 5905);
PAINT MONO (-4135 5905);
FORCEPROP 0 LAST $SEC 1
J 0
(-4175 6175);
DISPLAY 0.680851 (-4175 6175);
PAINT MONO (-4175 6175);
DISPLAY INVISIBLE (-4175 6175);
FORCEPROP 0 LAST CDS_SEC 1
J 0
(-4175 6175);
DISPLAY 0.680851 (-4175 6175);
DISPLAY INVISIBLE (-4175 6175);
FORCEADD UNIVERSAL_POWER..1
(-4125 6300);
FORCEPROP 3 LASTPIN (-4125 6250) SIG_NAME P3V3_AUX\g
J 0
(-4115 6260);
DISPLAY 0.659574 (-4115 6260);
PAINT MONO (-4115 6260);
DISPLAY INVISIBLE (-4115 6260);
FORCEPROP 1 LAST HDL_POWER P3V3_AUX
J 1
(-4125 6350);
DISPLAY 0.702128 (-4125 6350);
PAINT PEACH (-4125 6350);
FORCEPROP 1 LAST PATH I18
J 0
(-4075 6325);
DISPLAY 0.872340 (-4075 6325);
PAINT AQUA (-4075 6325);
DISPLAY INVISIBLE (-4075 6325);
FORCEPROP 2 LAST CDS_LIB logical_power
J 0
(-4125 6300);
DISPLAY INVISIBLE (-4125 6300);
FORCEADD OFFPAGE..2
(-2700 4300);
FORCEPROP 2 LAST $XR0 10 
J 0
(-2511 4300);
DISPLAY 0.638298 (-2511 4300);
PAINT MONO (-2511 4300);
FORCEPROP 1 LAST OFFPAGE TRUE
J 0
(-2375 4175);
DISPLAY 0.872340 (-2375 4175);
PAINT GREEN (-2375 4175);
DISPLAY INVISIBLE (-2375 4175);
FORCEPROP 1 LAST COMMENT_BODY TRUE
J 0
(-2745 4205);
DISPLAY 0.872340 (-2745 4205);
PAINT PEACH (-2745 4205);
DISPLAY INVISIBLE (-2745 4205);
FORCEPROP 2 LAST CDS_LIB standard
J 0
(-2700 4300);
DISPLAY INVISIBLE (-2700 4300);
FORCEPROP 2 LAST PATH I19
J 0
(-2500 4350);
DISPLAY 0.680851 (-2500 4350);
DISPLAY INVISIBLE (-2500 4350);
FORCEADD OFFPAGE..1
(-7200 4300);
FORCEPROP 2 LAST $XR0 12 
J 0
(-7421 4300);
DISPLAY 0.638298 (-7421 4300);
PAINT MONO (-7421 4300);
FORCEPROP 2 LAST CDS_LIB standard
J 0
(-7200 4300);
DISPLAY INVISIBLE (-7200 4300);
FORCEPROP 1 LAST COMMENT_BODY TRUE
J 0
(-7070 4200);
DISPLAY 1.106383 (-7070 4200);
PAINT PEACH (-7070 4200);
DISPLAY INVISIBLE (-7070 4200);
FORCEPROP 1 LAST OFFPAGE TRUE
J 0
(-6870 4170);
PAINT GREEN (-6870 4170);
DISPLAY INVISIBLE (-6870 4170);
FORCEPROP 2 LAST PATH I2
J 0
(-7450 4350);
DISPLAY 0.680851 (-7450 4350);
DISPLAY INVISIBLE (-7450 4350);
FORCEADD OFFPAGE..1
R 2
(-2700 4400);
FORCEPROP 2 LAST $XR0 13 
J 0
(-2514 4400);
DISPLAY 0.638298 (-2514 4400);
PAINT MONO (-2514 4400);
FORCEPROP 2 LAST $XR1 31 
J 0
(-2424 4400);
DISPLAY 0.638298 (-2424 4400);
PAINT MONO (-2424 4400);
FORCEPROP 1 LAST COMMENT_BODY TRUE
J 2
(-2825 4300);
DISPLAY 0.872340 (-2825 4300);
PAINT PEACH (-2825 4300);
DISPLAY INVISIBLE (-2825 4300);
FORCEPROP 1 LAST OFFPAGE TRUE
J 2
(-3025 4275);
DISPLAY 0.872340 (-3025 4275);
PAINT GREEN (-3025 4275);
DISPLAY INVISIBLE (-3025 4275);
FORCEPROP 2 LAST CDS_LIB standard
J 0
(-2700 4400);
DISPLAY INVISIBLE (-2700 4400);
FORCEPROP 2 LAST PATH I20
J 0
(-2400 4450);
DISPLAY 0.680851 (-2400 4450);
DISPLAY INVISIBLE (-2400 4450);
FORCEADD OFFPAGE..1
R 2
(-1375 5450);
FORCEPROP 2 LAST $XR0 10 
J 0
(-1189 5450);
DISPLAY 0.638298 (-1189 5450);
PAINT MONO (-1189 5450);
FORCEPROP 1 LAST OFFPAGE TRUE
J 2
(-1700 5325);
DISPLAY 0.872340 (-1700 5325);
PAINT GREEN (-1700 5325);
DISPLAY INVISIBLE (-1700 5325);
FORCEPROP 1 LAST COMMENT_BODY TRUE
J 2
(-1500 5350);
DISPLAY 0.872340 (-1500 5350);
PAINT PEACH (-1500 5350);
DISPLAY INVISIBLE (-1500 5350);
FORCEPROP 2 LAST CDS_LIB standard
J 0
(-1375 5450);
DISPLAY INVISIBLE (-1375 5450);
FORCEPROP 2 LAST PATH I21
J 0
(-1175 5500);
DISPLAY 0.680851 (-1175 5500);
DISPLAY INVISIBLE (-1175 5500);
FORCEADD OFFPAGE..1
R 2
(-2700 5550);
FORCEPROP 2 LAST $XR1 31 
J 0
(-2424 5550);
DISPLAY 0.638298 (-2424 5550);
PAINT MONO (-2424 5550);
FORCEPROP 2 LAST $XR0 13 
J 0
(-2514 5550);
DISPLAY 0.638298 (-2514 5550);
PAINT MONO (-2514 5550);
FORCEPROP 2 LAST CDS_LIB standard
J 0
(-2700 5550);
DISPLAY INVISIBLE (-2700 5550);
FORCEPROP 1 LAST COMMENT_BODY TRUE
J 2
(-2825 5450);
DISPLAY 0.872340 (-2825 5450);
PAINT PEACH (-2825 5450);
DISPLAY INVISIBLE (-2825 5450);
FORCEPROP 1 LAST OFFPAGE TRUE
J 2
(-3025 5425);
DISPLAY 0.872340 (-3025 5425);
PAINT GREEN (-3025 5425);
DISPLAY INVISIBLE (-3025 5425);
FORCEPROP 2 LAST PATH I22
J 0
(-2400 5600);
DISPLAY 0.680851 (-2400 5600);
DISPLAY INVISIBLE (-2400 5600);
FORCEADD NC7SB3157..1
(-4650 5550);
FORCEPROP 1 LAST PART_NUMBER ALSB3157000
J 0
(-4850 5695);
DISPLAY 0.723404 (-4850 5695);
PAINT GREEN (-4850 5695);
FORCEPROP 1 LAST VALUE NC7SB3157P6X
J 0
(-4850 5855);
DISPLAY 0.723404 (-4850 5855);
PAINT GREEN (-4850 5855);
FORCEPROP 2 LAST PATH I23
J 0
(-4848 5910);
DISPLAY 0.680851 (-4848 5910);
FORCEPROP 2 LAST MANUF_PN NC7SB3157P6X
J 0
(-4848 5960);
DISPLAY 0.680851 (-4848 5960);
FORCEPROP 1 LAST MATERIAL IC
J 0
(-4777 5630);
DISPLAY 0.723404 (-4777 5630);
PAINT GREEN (-4777 5630);
FORCEPROP 1 LAST PACK_TYPE SMLF
J 0
(-4650 5300);
DISPLAY 0.723404 (-4650 5300);
PAINT GREEN (-4650 5300);
DISPLAY INVISIBLE (-4650 5300);
FORCEPROP 1 LAST CDS_LMAN_SYM_OUTLINE -150,50,150,-150
J 0
(-4650 5550);
DISPLAY 0.468085 (-4650 5550);
PAINT GREEN (-4650 5550);
DISPLAY INVISIBLE (-4650 5550);
FORCEPROP 2 LAST CDS_LIB pure_quanta
J 0
(-4650 5550);
DISPLAY INVISIBLE (-4650 5550);
FORCEPROP 1 LAST LOCATION U50
J 0
(-4850 5775);
DISPLAY 0.723404 (-4850 5775);
PAINT GREEN (-4850 5775);
FORCEPROP 1 LASTPIN (-4350 5450) $PN 4
J 0
(-4460 5453);
DISPLAY 0.659574 (-4460 5453);
PAINT MONO (-4460 5453);
FORCEPROP 1 LASTPIN (-4950 5450) $PN 3
J 2
(-4840 5453);
DISPLAY 0.659574 (-4840 5453);
PAINT MONO (-4840 5453);
FORCEPROP 1 LASTPIN (-4950 5550) $PN 1
J 2
(-4840 5553);
DISPLAY 0.659574 (-4840 5553);
PAINT MONO (-4840 5553);
FORCEPROP 1 LASTPIN (-4950 5500) $PN 2
J 2
(-4840 5503);
DISPLAY 0.659574 (-4840 5503);
PAINT MONO (-4840 5503);
FORCEPROP 1 LASTPIN (-4350 5550) $PN 6
J 0
(-4460 5553);
DISPLAY 0.659574 (-4460 5553);
PAINT MONO (-4460 5553);
FORCEPROP 1 LASTPIN (-4350 5500) $PN 5
J 0
(-4460 5503);
DISPLAY 0.659574 (-4460 5503);
PAINT MONO (-4460 5503);
FORCEPROP 0 LAST $SEC 1
J 0
(-4825 6000);
DISPLAY 0.680851 (-4825 6000);
PAINT MONO (-4825 6000);
DISPLAY INVISIBLE (-4825 6000);
FORCEPROP 0 LAST CDS_SEC 1
J 0
(-4825 6000);
DISPLAY 0.680851 (-4825 6000);
DISPLAY INVISIBLE (-4825 6000);
FORCEADD NC7SB3157..1
(-4625 4400);
FORCEPROP 1 LAST MATERIAL IC
J 0
(-4752 4480);
DISPLAY 0.723404 (-4752 4480);
PAINT GREEN (-4752 4480);
FORCEPROP 1 LAST PART_NUMBER ALSB3157000
J 0
(-4852 4560);
DISPLAY 0.723404 (-4852 4560);
PAINT GREEN (-4852 4560);
FORCEPROP 1 LAST VALUE NC7SB3157P6X
J 0
(-4852 4720);
DISPLAY 0.723404 (-4852 4720);
PAINT GREEN (-4852 4720);
FORCEPROP 2 LAST MANUF_PN NC7SB3157P6X
J 0
(-4850 4825);
DISPLAY 0.680851 (-4850 4825);
FORCEPROP 2 LAST PATH I24
J 0
(-4850 4875);
DISPLAY 0.680851 (-4850 4875);
FORCEPROP 1 LAST PACK_TYPE SMLF
J 0
(-4625 4150);
DISPLAY 0.723404 (-4625 4150);
PAINT GREEN (-4625 4150);
DISPLAY INVISIBLE (-4625 4150);
FORCEPROP 1 LAST CDS_LMAN_SYM_OUTLINE -150,50,150,-150
J 0
(-4625 4400);
DISPLAY 0.468085 (-4625 4400);
PAINT GREEN (-4625 4400);
DISPLAY INVISIBLE (-4625 4400);
FORCEPROP 2 LAST CDS_LIB pure_quanta
J 0
(-4625 4400);
DISPLAY INVISIBLE (-4625 4400);
FORCEPROP 1 LAST LOCATION U51
J 0
(-4852 4640);
DISPLAY 0.723404 (-4852 4640);
PAINT GREEN (-4852 4640);
FORCEPROP 1 LASTPIN (-4325 4300) $PN 4
J 0
(-4435 4303);
DISPLAY 0.659574 (-4435 4303);
PAINT MONO (-4435 4303);
FORCEPROP 1 LASTPIN (-4925 4300) $PN 3
J 2
(-4815 4303);
DISPLAY 0.659574 (-4815 4303);
PAINT MONO (-4815 4303);
FORCEPROP 1 LASTPIN (-4925 4400) $PN 1
J 2
(-4815 4403);
DISPLAY 0.659574 (-4815 4403);
PAINT MONO (-4815 4403);
FORCEPROP 1 LASTPIN (-4925 4350) $PN 2
J 2
(-4815 4353);
DISPLAY 0.659574 (-4815 4353);
PAINT MONO (-4815 4353);
FORCEPROP 1 LASTPIN (-4325 4400) $PN 6
J 0
(-4435 4403);
DISPLAY 0.659574 (-4435 4403);
PAINT MONO (-4435 4403);
FORCEPROP 1 LASTPIN (-4325 4350) $PN 5
J 0
(-4435 4353);
DISPLAY 0.659574 (-4435 4353);
PAINT MONO (-4435 4353);
FORCEPROP 0 LAST $SEC 1
J 0
(-4850 4925);
DISPLAY 0.680851 (-4850 4925);
PAINT MONO (-4850 4925);
DISPLAY INVISIBLE (-4850 4925);
FORCEPROP 0 LAST CDS_SEC 1
J 0
(-4850 4925);
DISPLAY 0.680851 (-4850 4925);
DISPLAY INVISIBLE (-4850 4925);
FORCEADD Q_RES..2
(-5900 6050);
FORCEPROP 1 LAST VALUE 100K
J 0
(-5855 6125);
DISPLAY 0.787234 (-5855 6125);
FORCEPROP 1 LAST TOLERANCE 1%
J 0
(-5855 6075);
DISPLAY 0.787234 (-5855 6075);
FORCEPROP 1 LAST MATERIAL CHIP
J 0
(-5860 5975);
DISPLAY 0.787234 (-5860 5975);
FORCEPROP 1 LAST WATTAGE 1/16W
J 0
(-5860 6025);
DISPLAY 0.787234 (-5860 6025);
FORCEPROP 1 LAST PART_NUMBER CS41002FB09
J 0
(-5860 5925);
DISPLAY 0.787234 (-5860 5925);
FORCEPROP 1 LAST PACK_TYPE 0402LF
J 0
(-5860 5875);
DISPLAY 0.787234 (-5860 5875);
FORCEPROP 2 LAST CDS_LIB pure_quanta
J 0
(-5900 6050);
DISPLAY INVISIBLE (-5900 6050);
FORCEPROP 1 LAST PATH I25
J 0
(-5850 6225);
DISPLAY 0.978723 (-5850 6225);
PAINT WHITE (-5850 6225);
DISPLAY INVISIBLE (-5850 6225);
FORCEPROP 1 LAST $LOCATION R538
J 0
(-5855 6175);
DISPLAY 0.787234 (-5855 6175);
FORCEPROP 1 LASTPIN (-5900 6150) $PN 1
J 0
(-5895 6112);
DISPLAY 0.787234 (-5895 6112);
PAINT MONO (-5895 6112);
FORCEPROP 1 LASTPIN (-5900 5950) $PN 2
J 0
(-5895 5960);
DISPLAY 0.787234 (-5895 5960);
PAINT MONO (-5895 5960);
FORCEPROP 0 LAST CDS_LOCATION R538
J 0
(-5850 6225);
DISPLAY 0.680851 (-5850 6225);
DISPLAY INVISIBLE (-5850 6225);
FORCEPROP 0 LAST $SEC 1
J 0
(-5850 6225);
DISPLAY 0.680851 (-5850 6225);
PAINT MONO (-5850 6225);
DISPLAY INVISIBLE (-5850 6225);
FORCEPROP 0 LAST CDS_SEC 1
J 0
(-5850 6225);
DISPLAY 0.680851 (-5850 6225);
DISPLAY INVISIBLE (-5850 6225);
FORCEADD UNIVERSAL_POWER..1
(-5900 6325);
FORCEPROP 3 LASTPIN (-5900 6275) SIG_NAME P3V3_AUX\g
J 0
(-5890 6285);
DISPLAY 0.659574 (-5890 6285);
PAINT MONO (-5890 6285);
DISPLAY INVISIBLE (-5890 6285);
FORCEPROP 1 LAST HDL_POWER P3V3_AUX
J 1
(-5900 6375);
DISPLAY 0.702128 (-5900 6375);
PAINT PEACH (-5900 6375);
FORCEPROP 2 LAST CDS_LIB logical_power
J 0
(-5900 6325);
DISPLAY INVISIBLE (-5900 6325);
FORCEPROP 1 LAST PATH I26
J 0
(-5850 6350);
DISPLAY 0.872340 (-5850 6350);
PAINT AQUA (-5850 6350);
DISPLAY INVISIBLE (-5850 6350);
FORCEADD NC7SB3157..1
(-4600 2925);
FORCEPROP 2 LAST PATH I27
J 0
(-4825 3400);
DISPLAY 0.680851 (-4825 3400);
FORCEPROP 1 LAST VALUE NC7SB3157P6X
J 0
(-4827 3245);
DISPLAY 0.723404 (-4827 3245);
PAINT GREEN (-4827 3245);
FORCEPROP 1 LAST MATERIAL IC
J 0
(-4727 3005);
DISPLAY 0.723404 (-4727 3005);
PAINT GREEN (-4727 3005);
FORCEPROP 1 LAST PART_NUMBER ALSB3157000
J 0
(-4827 3085);
DISPLAY 0.723404 (-4827 3085);
PAINT GREEN (-4827 3085);
FORCEPROP 2 LAST MANUF_PN NC7SB3157P6X
J 0
(-4825 3350);
DISPLAY 0.680851 (-4825 3350);
FORCEPROP 2 LAST CDS_LIB pure_quanta
J 0
(-4600 2925);
DISPLAY INVISIBLE (-4600 2925);
FORCEPROP 1 LAST CDS_LMAN_SYM_OUTLINE -150,50,150,-150
J 0
(-4600 2925);
DISPLAY 0.468085 (-4600 2925);
PAINT GREEN (-4600 2925);
DISPLAY INVISIBLE (-4600 2925);
FORCEPROP 1 LAST PACK_TYPE SMLF
J 0
(-4600 2675);
DISPLAY 0.723404 (-4600 2675);
PAINT GREEN (-4600 2675);
DISPLAY INVISIBLE (-4600 2675);
FORCEPROP 1 LAST $LOCATION U7
J 0
(-4827 3165);
DISPLAY 0.723404 (-4827 3165);
PAINT GREEN (-4827 3165);
FORCEPROP 1 LASTPIN (-4300 2825) $PN 4
J 0
(-4410 2828);
DISPLAY 0.659574 (-4410 2828);
PAINT MONO (-4410 2828);
FORCEPROP 1 LASTPIN (-4900 2825) $PN 3
J 2
(-4790 2828);
DISPLAY 0.659574 (-4790 2828);
PAINT MONO (-4790 2828);
FORCEPROP 1 LASTPIN (-4900 2925) $PN 1
J 2
(-4790 2928);
DISPLAY 0.659574 (-4790 2928);
PAINT MONO (-4790 2928);
FORCEPROP 1 LASTPIN (-4900 2875) $PN 2
J 2
(-4790 2878);
DISPLAY 0.659574 (-4790 2878);
PAINT MONO (-4790 2878);
FORCEPROP 1 LASTPIN (-4300 2925) $PN 6
J 0
(-4410 2928);
DISPLAY 0.659574 (-4410 2928);
PAINT MONO (-4410 2928);
FORCEPROP 1 LASTPIN (-4300 2875) $PN 5
J 0
(-4410 2878);
DISPLAY 0.659574 (-4410 2878);
PAINT MONO (-4410 2878);
FORCEPROP 0 LAST CDS_LOCATION U7
J 0
(-4825 3450);
DISPLAY 0.680851 (-4825 3450);
DISPLAY INVISIBLE (-4825 3450);
FORCEPROP 0 LAST $SEC 1
J 0
(-4825 3450);
DISPLAY 0.680851 (-4825 3450);
PAINT MONO (-4825 3450);
DISPLAY INVISIBLE (-4825 3450);
FORCEPROP 0 LAST CDS_SEC 1
J 0
(-4825 3450);
DISPLAY 0.680851 (-4825 3450);
DISPLAY INVISIBLE (-4825 3450);
FORCEADD OFFPAGE..1
R 2
(-2675 2925);
FORCEPROP 2 LAST $XR0 31 
J 0
(-2489 2925);
DISPLAY 0.638298 (-2489 2925);
PAINT MONO (-2489 2925);
FORCEPROP 1 LAST OFFPAGE TRUE
J 2
(-3000 2800);
DISPLAY 0.872340 (-3000 2800);
PAINT GREEN (-3000 2800);
DISPLAY INVISIBLE (-3000 2800);
FORCEPROP 1 LAST COMMENT_BODY TRUE
J 2
(-2800 2825);
DISPLAY 0.872340 (-2800 2825);
PAINT PEACH (-2800 2825);
DISPLAY INVISIBLE (-2800 2825);
FORCEPROP 2 LAST PATH I28
J 0
(-2375 2975);
DISPLAY 0.680851 (-2375 2975);
DISPLAY INVISIBLE (-2375 2975);
FORCEPROP 2 LAST CDS_LIB standard
J 0
(-2675 2925);
DISPLAY INVISIBLE (-2675 2925);
FORCEADD OFFPAGE..2
R 2
(-7225 5550);
FORCEPROP 2 LAST $XR0 30 
J 0
(-7449 5550);
DISPLAY 0.638298 (-7449 5550);
PAINT MONO (-7449 5550);
FORCEPROP 2 LAST PATH I3
J 0
(-7475 5600);
DISPLAY 0.680851 (-7475 5600);
DISPLAY INVISIBLE (-7475 5600);
FORCEPROP 1 LAST OFFPAGE TRUE
J 2
(-7550 5425);
DISPLAY 0.872340 (-7550 5425);
PAINT GREEN (-7550 5425);
DISPLAY INVISIBLE (-7550 5425);
FORCEPROP 1 LAST COMMENT_BODY TRUE
J 2
(-7180 5455);
DISPLAY 0.872340 (-7180 5455);
PAINT PEACH (-7180 5455);
DISPLAY INVISIBLE (-7180 5455);
FORCEPROP 2 LAST CDS_LIB standard
J 0
(-7225 5550);
DISPLAY INVISIBLE (-7225 5550);
FORCEADD UNIVERSAL_POWER..1
(-4125 3625);
FORCEPROP 3 LASTPIN (-4125 3575) SIG_NAME P3V3_AUX\g
J 0
(-4115 3585);
DISPLAY 0.659574 (-4115 3585);
PAINT MONO (-4115 3585);
DISPLAY INVISIBLE (-4115 3585);
FORCEPROP 1 LAST HDL_POWER P3V3_AUX
J 1
(-4125 3675);
DISPLAY 0.702128 (-4125 3675);
PAINT PEACH (-4125 3675);
FORCEPROP 2 LAST CDS_LIB logical_power
J 0
(-4125 3625);
DISPLAY INVISIBLE (-4125 3625);
FORCEPROP 1 LAST PATH I30
J 0
(-4075 3650);
DISPLAY 0.872340 (-4075 3650);
PAINT AQUA (-4075 3650);
DISPLAY INVISIBLE (-4075 3650);
FORCEADD Q_CAP..1
R 2
(-4125 3350);
FORCEPROP 1 LAST VOLTAGE 25V
J 2
(-4175 3350);
DISPLAY 0.510638 (-4175 3350);
PAINT SKYBLUE (-4175 3350);
FORCEPROP 1 LAST PACK_TYPE 0402
J 2
(-4175 3150);
DISPLAY 0.510638 (-4175 3150);
PAINT SKYBLUE (-4175 3150);
FORCEPROP 1 LAST PART_NUMBER CH4104K1B00
J 2
(-4175 3200);
DISPLAY 0.510638 (-4175 3200);
PAINT WHITE (-4175 3200);
FORCEPROP 1 LAST MATERIAL X7R
J 2
(-4175 3250);
DISPLAY 0.510638 (-4175 3250);
PAINT SKYBLUE (-4175 3250);
FORCEPROP 1 LAST TOLERANCE 10%
J 2
(-4175 3300);
DISPLAY 0.510638 (-4175 3300);
PAINT SKYBLUE (-4175 3300);
FORCEPROP 1 LAST VALUE 0.1UF
J 2
(-4200 3400);
DISPLAY 0.510638 (-4200 3400);
PAINT SKYBLUE (-4200 3400);
FORCEPROP 2 LAST CDS_LIB pure_quanta
J 0
(-4125 3350);
DISPLAY INVISIBLE (-4125 3350);
FORCEPROP 1 LAST PATH I31
J 2
(-4175 3500);
DISPLAY 0.978723 (-4175 3500);
PAINT WHITE (-4175 3500);
DISPLAY INVISIBLE (-4175 3500);
FORCEPROP 1 LAST $LOCATION C11
J 2
(-4175 3450);
DISPLAY 0.702128 (-4175 3450);
PAINT YELLOW (-4175 3450);
FORCEPROP 1 LASTPIN (-4125 3450) $PN 1
J 2
(-4135 3430);
DISPLAY 0.787234 (-4135 3430);
PAINT MONO (-4135 3430);
FORCEPROP 1 LASTPIN (-4125 3250) $PN 2
J 2
(-4135 3230);
DISPLAY 0.787234 (-4135 3230);
PAINT MONO (-4135 3230);
FORCEPROP 0 LAST CDS_LOCATION C11
J 0
(-4175 3500);
DISPLAY 0.680851 (-4175 3500);
DISPLAY INVISIBLE (-4175 3500);
FORCEPROP 0 LAST $SEC 1
J 0
(-4175 3500);
DISPLAY 0.680851 (-4175 3500);
PAINT MONO (-4175 3500);
DISPLAY INVISIBLE (-4175 3500);
FORCEPROP 0 LAST CDS_SEC 1
J 0
(-4175 3500);
DISPLAY 0.680851 (-4175 3500);
DISPLAY INVISIBLE (-4175 3500);
FORCEADD UNIVERSAL_GND..1
R 2
(-4125 3150);
FORCEPROP 3 LASTPIN (-4125 3200) SIG_NAME GND\g
J 0
(-4115 3210);
DISPLAY 0.659574 (-4115 3210);
PAINT MONO (-4115 3210);
DISPLAY INVISIBLE (-4115 3210);
FORCEPROP 1 LAST HDL_POWER GND
J 1
(-4150 3075);
DISPLAY 0.702128 (-4150 3075);
PAINT GREEN (-4150 3075);
DISPLAY INVISIBLE (-4150 3075);
FORCEPROP 2 LAST CDS_LIB logical_power
J 0
(-4125 3150);
DISPLAY INVISIBLE (-4125 3150);
FORCEPROP 1 LAST PATH I32
J 2
(-4200 3150);
DISPLAY 0.872340 (-4200 3150);
PAINT AQUA (-4200 3150);
DISPLAY INVISIBLE (-4200 3150);
FORCEADD UNIVERSAL_GND..1
R 2
(-5025 2650);
FORCEPROP 3 LASTPIN (-5025 2700) SIG_NAME GND\g
J 0
(-5015 2710);
DISPLAY 0.659574 (-5015 2710);
PAINT MONO (-5015 2710);
DISPLAY INVISIBLE (-5015 2710);
FORCEPROP 2 LAST CDS_LIB logical_power
J 0
(-5025 2650);
DISPLAY INVISIBLE (-5025 2650);
FORCEPROP 1 LAST HDL_POWER GND
J 1
(-5050 2575);
DISPLAY 0.702128 (-5050 2575);
PAINT GREEN (-5050 2575);
DISPLAY INVISIBLE (-5050 2575);
FORCEPROP 1 LAST PATH I33
J 2
(-5100 2650);
DISPLAY 0.872340 (-5100 2650);
PAINT AQUA (-5100 2650);
DISPLAY INVISIBLE (-5100 2650);
FORCEADD NC7SB3157..1
(-4500 1325);
FORCEPROP 2 LAST MANUF_PN NC7SB3157P6X
J 0
(-4725 1750);
DISPLAY 0.680851 (-4725 1750);
FORCEPROP 2 LAST PATH I38
J 0
(-4725 1800);
DISPLAY 0.680851 (-4725 1800);
FORCEPROP 1 LAST VALUE NC7SB3157P6X
J 0
(-4727 1645);
DISPLAY 0.723404 (-4727 1645);
PAINT GREEN (-4727 1645);
FORCEPROP 1 LAST PART_NUMBER ALSB3157000
J 0
(-4727 1485);
DISPLAY 0.723404 (-4727 1485);
PAINT GREEN (-4727 1485);
FORCEPROP 1 LAST MATERIAL IC
J 0
(-4627 1405);
DISPLAY 0.723404 (-4627 1405);
PAINT GREEN (-4627 1405);
FORCEPROP 1 LAST PACK_TYPE SMLF
J 0
(-4500 1075);
DISPLAY 0.723404 (-4500 1075);
PAINT GREEN (-4500 1075);
DISPLAY INVISIBLE (-4500 1075);
FORCEPROP 1 LAST CDS_LMAN_SYM_OUTLINE -150,50,150,-150
J 0
(-4500 1325);
DISPLAY 0.468085 (-4500 1325);
PAINT GREEN (-4500 1325);
DISPLAY INVISIBLE (-4500 1325);
FORCEPROP 2 LAST CDS_LIB pure_quanta
J 0
(-4500 1325);
DISPLAY INVISIBLE (-4500 1325);
FORCEPROP 1 LAST $LOCATION U20
J 0
(-4727 1565);
DISPLAY 0.723404 (-4727 1565);
PAINT GREEN (-4727 1565);
FORCEPROP 1 LASTPIN (-4200 1225) $PN 4
J 0
(-4310 1228);
DISPLAY 0.659574 (-4310 1228);
PAINT MONO (-4310 1228);
FORCEPROP 1 LASTPIN (-4800 1225) $PN 3
J 2
(-4690 1228);
DISPLAY 0.659574 (-4690 1228);
PAINT MONO (-4690 1228);
FORCEPROP 1 LASTPIN (-4800 1325) $PN 1
J 2
(-4690 1328);
DISPLAY 0.659574 (-4690 1328);
PAINT MONO (-4690 1328);
FORCEPROP 1 LASTPIN (-4800 1275) $PN 2
J 2
(-4690 1278);
DISPLAY 0.659574 (-4690 1278);
PAINT MONO (-4690 1278);
FORCEPROP 1 LASTPIN (-4200 1325) $PN 6
J 0
(-4310 1328);
DISPLAY 0.659574 (-4310 1328);
PAINT MONO (-4310 1328);
FORCEPROP 1 LASTPIN (-4200 1275) $PN 5
J 0
(-4310 1278);
DISPLAY 0.659574 (-4310 1278);
PAINT MONO (-4310 1278);
FORCEPROP 0 LAST CDS_LOCATION U20
J 0
(-4725 1850);
DISPLAY 0.680851 (-4725 1850);
DISPLAY INVISIBLE (-4725 1850);
FORCEPROP 0 LAST $SEC 1
J 0
(-4725 1850);
DISPLAY 0.680851 (-4725 1850);
PAINT MONO (-4725 1850);
DISPLAY INVISIBLE (-4725 1850);
FORCEPROP 0 LAST CDS_SEC 1
J 0
(-4725 1850);
DISPLAY 0.680851 (-4725 1850);
DISPLAY INVISIBLE (-4725 1850);
FORCEADD OFFPAGE..2
R 2
(-7225 5450);
FORCEPROP 2 LAST $XR0 12 
J 0
(-7449 5450);
DISPLAY 0.638298 (-7449 5450);
PAINT MONO (-7449 5450);
FORCEPROP 1 LAST COMMENT_BODY TRUE
J 2
(-7180 5355);
DISPLAY 0.872340 (-7180 5355);
PAINT PEACH (-7180 5355);
DISPLAY INVISIBLE (-7180 5355);
FORCEPROP 1 LAST OFFPAGE TRUE
J 2
(-7550 5325);
DISPLAY 0.872340 (-7550 5325);
PAINT GREEN (-7550 5325);
DISPLAY INVISIBLE (-7550 5325);
FORCEPROP 2 LAST PATH I4
J 0
(-7475 5500);
DISPLAY 0.680851 (-7475 5500);
DISPLAY INVISIBLE (-7475 5500);
FORCEPROP 2 LAST CDS_LIB standard
J 0
(-7225 5450);
DISPLAY INVISIBLE (-7225 5450);
FORCEADD UNIVERSAL_GND..1
R 2
(-4925 1050);
FORCEPROP 3 LASTPIN (-4925 1100) SIG_NAME GND\g
J 0
(-4915 1110);
DISPLAY 0.659574 (-4915 1110);
PAINT MONO (-4915 1110);
DISPLAY INVISIBLE (-4915 1110);
FORCEPROP 2 LAST CDS_LIB logical_power
J 0
(-4925 1050);
DISPLAY INVISIBLE (-4925 1050);
FORCEPROP 1 LAST PATH I43
J 2
(-5000 1050);
DISPLAY 0.872340 (-5000 1050);
PAINT AQUA (-5000 1050);
DISPLAY INVISIBLE (-5000 1050);
FORCEPROP 1 LAST HDL_POWER GND
J 1
(-4950 975);
DISPLAY 0.702128 (-4950 975);
PAINT GREEN (-4950 975);
DISPLAY INVISIBLE (-4950 975);
FORCEADD UNIVERSAL_GND..1
R 2
(-4025 1550);
FORCEPROP 3 LASTPIN (-4025 1600) SIG_NAME GND\g
J 0
(-4015 1610);
DISPLAY 0.659574 (-4015 1610);
PAINT MONO (-4015 1610);
DISPLAY INVISIBLE (-4015 1610);
FORCEPROP 1 LAST PATH I44
J 2
(-4100 1550);
DISPLAY 0.872340 (-4100 1550);
PAINT AQUA (-4100 1550);
DISPLAY INVISIBLE (-4100 1550);
FORCEPROP 2 LAST CDS_LIB logical_power
J 0
(-4025 1550);
DISPLAY INVISIBLE (-4025 1550);
FORCEPROP 1 LAST HDL_POWER GND
J 1
(-4050 1475);
DISPLAY 0.702128 (-4050 1475);
PAINT GREEN (-4050 1475);
DISPLAY INVISIBLE (-4050 1475);
FORCEADD Q_CAP..1
R 2
(-4025 1750);
FORCEPROP 1 LAST PACK_TYPE 0402
J 2
(-4075 1550);
DISPLAY 0.510638 (-4075 1550);
PAINT SKYBLUE (-4075 1550);
FORCEPROP 1 LAST MATERIAL X7R
J 2
(-4075 1650);
DISPLAY 0.510638 (-4075 1650);
PAINT SKYBLUE (-4075 1650);
FORCEPROP 1 LAST TOLERANCE 10%
J 2
(-4075 1700);
DISPLAY 0.510638 (-4075 1700);
PAINT SKYBLUE (-4075 1700);
FORCEPROP 1 LAST PART_NUMBER CH4104K1B00
J 2
(-4075 1600);
DISPLAY 0.510638 (-4075 1600);
PAINT WHITE (-4075 1600);
FORCEPROP 1 LAST VOLTAGE 25V
J 2
(-4075 1750);
DISPLAY 0.510638 (-4075 1750);
PAINT SKYBLUE (-4075 1750);
FORCEPROP 1 LAST VALUE 0.1UF
J 2
(-4100 1800);
DISPLAY 0.510638 (-4100 1800);
PAINT SKYBLUE (-4100 1800);
FORCEPROP 1 LAST PATH I45
J 2
(-4075 1900);
DISPLAY 0.978723 (-4075 1900);
PAINT WHITE (-4075 1900);
DISPLAY INVISIBLE (-4075 1900);
FORCEPROP 2 LAST CDS_LIB pure_quanta
J 0
(-4025 1750);
DISPLAY INVISIBLE (-4025 1750);
FORCEPROP 1 LAST $LOCATION C231
J 2
(-4075 1850);
DISPLAY 0.702128 (-4075 1850);
PAINT YELLOW (-4075 1850);
FORCEPROP 1 LASTPIN (-4025 1850) $PN 1
J 2
(-4035 1830);
DISPLAY 0.787234 (-4035 1830);
PAINT MONO (-4035 1830);
FORCEPROP 1 LASTPIN (-4025 1650) $PN 2
J 2
(-4035 1630);
DISPLAY 0.787234 (-4035 1630);
PAINT MONO (-4035 1630);
FORCEPROP 0 LAST CDS_LOCATION C231
J 0
(-4075 1900);
DISPLAY 0.680851 (-4075 1900);
DISPLAY INVISIBLE (-4075 1900);
FORCEPROP 0 LAST $SEC 1
J 0
(-4075 1900);
DISPLAY 0.680851 (-4075 1900);
PAINT MONO (-4075 1900);
DISPLAY INVISIBLE (-4075 1900);
FORCEPROP 0 LAST CDS_SEC 1
J 0
(-4075 1900);
DISPLAY 0.680851 (-4075 1900);
DISPLAY INVISIBLE (-4075 1900);
FORCEADD UNIVERSAL_POWER..1
(-4025 2025);
FORCEPROP 3 LASTPIN (-4025 1975) SIG_NAME P3V3_AUX\g
J 0
(-4015 1985);
DISPLAY 0.659574 (-4015 1985);
PAINT MONO (-4015 1985);
DISPLAY INVISIBLE (-4015 1985);
FORCEPROP 1 LAST HDL_POWER P3V3_AUX
J 1
(-4025 2075);
DISPLAY 0.702128 (-4025 2075);
PAINT PEACH (-4025 2075);
FORCEPROP 1 LAST PATH I46
J 0
(-3975 2050);
DISPLAY 0.872340 (-3975 2050);
PAINT AQUA (-3975 2050);
DISPLAY INVISIBLE (-3975 2050);
FORCEPROP 2 LAST CDS_LIB logical_power
J 0
(-4025 2025);
DISPLAY INVISIBLE (-4025 2025);
FORCEADD OFFPAGE..1
R 2
(-2575 1325);
FORCEPROP 2 LAST $XR0 31 
J 0
(-2389 1325);
DISPLAY 0.638298 (-2389 1325);
PAINT MONO (-2389 1325);
FORCEPROP 2 LAST PATH I47
J 0
(-2275 1375);
DISPLAY 0.680851 (-2275 1375);
DISPLAY INVISIBLE (-2275 1375);
FORCEPROP 1 LAST COMMENT_BODY TRUE
J 2
(-2700 1225);
DISPLAY 0.872340 (-2700 1225);
PAINT PEACH (-2700 1225);
DISPLAY INVISIBLE (-2700 1225);
FORCEPROP 1 LAST OFFPAGE TRUE
J 2
(-2900 1200);
DISPLAY 0.872340 (-2900 1200);
PAINT GREEN (-2900 1200);
DISPLAY INVISIBLE (-2900 1200);
FORCEPROP 2 LAST CDS_LIB standard
J 0
(-2575 1325);
DISPLAY INVISIBLE (-2575 1325);
FORCEADD OFFPAGE..2
(-2575 1225);
FORCEPROP 2 LAST $XR0 30 
J 0
(-2386 1225);
DISPLAY 0.638298 (-2386 1225);
PAINT MONO (-2386 1225);
FORCEPROP 2 LAST PATH I48
J 0
(-2375 1275);
DISPLAY 0.680851 (-2375 1275);
DISPLAY INVISIBLE (-2375 1275);
FORCEPROP 1 LAST OFFPAGE TRUE
J 0
(-2250 1100);
DISPLAY 0.872340 (-2250 1100);
PAINT GREEN (-2250 1100);
DISPLAY INVISIBLE (-2250 1100);
FORCEPROP 1 LAST COMMENT_BODY TRUE
J 0
(-2620 1130);
DISPLAY 0.872340 (-2620 1130);
PAINT PEACH (-2620 1130);
DISPLAY INVISIBLE (-2620 1130);
FORCEPROP 2 LAST CDS_LIB standard
J 0
(-2575 1225);
DISPLAY INVISIBLE (-2575 1225);
FORCEADD OFFPAGE..1
R 2
(-2675 2825);
FORCEPROP 2 LAST $XR0 30 
J 0
(-2489 2825);
DISPLAY 0.638298 (-2489 2825);
PAINT MONO (-2489 2825);
FORCEPROP 2 LAST CDS_LIB standard
J 0
(-2675 2825);
DISPLAY INVISIBLE (-2675 2825);
FORCEPROP 2 LAST PATH I49
J 0
(-2500 2900);
DISPLAY 0.680851 (-2500 2900);
DISPLAY INVISIBLE (-2500 2900);
FORCEPROP 1 LAST COMMENT_BODY TRUE
J 2
(-2800 2725);
DISPLAY 0.872340 (-2800 2725);
PAINT PEACH (-2800 2725);
DISPLAY INVISIBLE (-2800 2725);
FORCEPROP 1 LAST OFFPAGE TRUE
J 2
(-3000 2700);
DISPLAY 0.872340 (-3000 2700);
PAINT GREEN (-3000 2700);
DISPLAY INVISIBLE (-3000 2700);
FORCEADD UNIVERSAL_GND..1
R 2
(-2100 1750);
FORCEPROP 3 LASTPIN (-2100 1800) SIG_NAME GND\g
J 0
(-2090 1810);
DISPLAY 0.659574 (-2090 1810);
PAINT MONO (-2090 1810);
DISPLAY INVISIBLE (-2090 1810);
FORCEPROP 1 LAST HDL_POWER GND
J 1
(-2125 1675);
DISPLAY 0.702128 (-2125 1675);
PAINT GREEN (-2125 1675);
DISPLAY INVISIBLE (-2125 1675);
FORCEPROP 1 LAST PATH I52
J 2
(-2175 1750);
DISPLAY 0.872340 (-2175 1750);
PAINT AQUA (-2175 1750);
DISPLAY INVISIBLE (-2175 1750);
FORCEPROP 2 LAST CDS_LIB logical_power
J 0
(-2100 1750);
DISPLAY INVISIBLE (-2100 1750);
FORCEADD UNIVERSAL_POWER..1
(-2175 2550);
FORCEPROP 3 LASTPIN (-2175 2500) SIG_NAME P3V3_AUX\g
J 0
(-2165 2510);
DISPLAY 0.659574 (-2165 2510);
PAINT MONO (-2165 2510);
DISPLAY INVISIBLE (-2165 2510);
FORCEPROP 1 LAST HDL_POWER P3V3_AUX
J 1
(-2175 2600);
DISPLAY 0.702128 (-2175 2600);
PAINT GREEN (-2175 2600);
FORCEPROP 1 LAST PATH I54
J 0
(-2125 2575);
DISPLAY 0.872340 (-2125 2575);
PAINT AQUA (-2125 2575);
DISPLAY INVISIBLE (-2125 2575);
FORCEPROP 2 LAST CDS_LIB logical_power
J 0
(-2175 2550);
DISPLAY INVISIBLE (-2175 2550);
FORCEADD OFFPAGE..2
R 2
(-3500 2025);
FORCEPROP 2 LAST $XR0 31 
J 0
(-3724 2025);
DISPLAY 0.638298 (-3724 2025);
PAINT MONO (-3724 2025);
FORCEPROP 1 LAST OFFPAGE TRUE
J 2
(-3825 1900);
DISPLAY 0.872340 (-3825 1900);
PAINT GREEN (-3825 1900);
DISPLAY INVISIBLE (-3825 1900);
FORCEPROP 1 LAST COMMENT_BODY TRUE
J 2
(-3455 1930);
DISPLAY 0.872340 (-3455 1930);
PAINT PEACH (-3455 1930);
DISPLAY INVISIBLE (-3455 1930);
FORCEPROP 2 LAST PATH I56
J 0
(-3450 2100);
DISPLAY 0.680851 (-3450 2100);
DISPLAY INVISIBLE (-3450 2100);
FORCEPROP 2 LAST CDS_LIB standard
J 0
(-3500 2025);
DISPLAY INVISIBLE (-3500 2025);
FORCEADD OFFPAGE..1
(-3475 2225);
FORCEPROP 2 LAST $XR0 13 
J 0
(-3726 2225);
DISPLAY 0.638298 (-3726 2225);
PAINT MONO (-3726 2225);
FORCEPROP 2 LAST $XR1 34 
J 0
(-3816 2225);
DISPLAY 0.638298 (-3816 2225);
PAINT MONO (-3816 2225);
FORCEPROP 2 LAST $XR2 42 
J 0
(-3906 2225);
DISPLAY 0.638298 (-3906 2225);
PAINT MONO (-3906 2225);
FORCEPROP 1 LAST COMMENT_BODY TRUE
J 0
(-3345 2125);
DISPLAY 1.106383 (-3345 2125);
PAINT PEACH (-3345 2125);
DISPLAY INVISIBLE (-3345 2125);
FORCEPROP 1 LAST OFFPAGE TRUE
J 0
(-3145 2095);
PAINT GREEN (-3145 2095);
DISPLAY INVISIBLE (-3145 2095);
FORCEPROP 2 LAST PATH I59
J 0
(-3425 2300);
DISPLAY 0.680851 (-3425 2300);
DISPLAY INVISIBLE (-3425 2300);
FORCEPROP 2 LAST CDS_LIB standard
J 0
(-3475 2225);
DISPLAY INVISIBLE (-3475 2225);
FORCEADD SCONN3_212H9103GBR1..1
(-1450 2025);
FORCEPROP 2 LAST PART_TYPE SMLF
J 0
(-1500 2400);
DISPLAY 0.680851 (-1500 2400);
FORCEPROP 2 LAST VALUE SCONN3_212-H91-03GBR1
J 0
(-1500 2350);
DISPLAY 0.680851 (-1500 2350);
FORCEPROP 1 LAST PART_NUMBER DFHD03MS161
J 0
(-1500 2225);
DISPLAY 0.723404 (-1500 2225);
PAINT GREEN (-1500 2225);
FORCEPROP 1 LAST MATERIAL EMPTY
J 0
(-1500 2150);
DISPLAY 0.723404 (-1500 2150);
PAINT GREEN (-1500 2150);
FORCEPROP 1 LAST NEEDS_NO_SIZE TRUE
J 0
(-1450 2025);
DISPLAY 0.723404 (-1450 2025);
PAINT GREEN (-1450 2025);
DISPLAY INVISIBLE (-1450 2025);
FORCEPROP 1 LAST PATH I61
J 0
(-1450 2025);
DISPLAY 0.723404 (-1450 2025);
PAINT GREEN (-1450 2025);
DISPLAY INVISIBLE (-1450 2025);
FORCEPROP 1 LAST CDS_LMAN_SYM_OUTLINE -50,100,50,-100
J 0
(-1450 2025);
DISPLAY 0.468085 (-1450 2025);
PAINT GREEN (-1450 2025);
DISPLAY INVISIBLE (-1450 2025);
FORCEPROP 2 LAST CDS_LIB pure_quanta
J 0
(-1450 2025);
DISPLAY INVISIBLE (-1450 2025);
FORCEPROP 1 LAST LOCATION J13
J 0
(-1500 2300);
DISPLAY 0.723404 (-1500 2300);
PAINT GREEN (-1500 2300);
FORCEPROP 0 LASTPIN (-1650 2075) $PN 1
J 2
(-1660 2085);
DISPLAY 0.680851 (-1660 2085);
PAINT MONO (-1660 2085);
FORCEPROP 0 LASTPIN (-1650 2025) $PN 2
J 2
(-1660 2035);
DISPLAY 0.680851 (-1660 2035);
PAINT MONO (-1660 2035);
FORCEPROP 0 LASTPIN (-1650 1975) $PN 3
J 2
(-1660 1985);
DISPLAY 0.680851 (-1660 1985);
PAINT MONO (-1660 1985);
FORCEPROP 0 LAST $SEC 1
J 0
(-1500 2450);
DISPLAY 0.680851 (-1500 2450);
PAINT MONO (-1500 2450);
DISPLAY INVISIBLE (-1500 2450);
FORCEPROP 0 LAST CDS_SEC 1
J 0
(-1500 2450);
DISPLAY 0.680851 (-1500 2450);
DISPLAY INVISIBLE (-1500 2450);
FORCEADD OFFPAGE..2
R 2
(-7175 2925);
FORCEPROP 2 LAST $XR0 29 
J 0
(-7429 2925);
DISPLAY 0.638298 (-7429 2925);
PAINT MONO (-7429 2925);
FORCEPROP 1 LAST OFFPAGE TRUE
J 2
(-7500 2800);
DISPLAY 0.872340 (-7500 2800);
PAINT GREEN (-7500 2800);
DISPLAY INVISIBLE (-7500 2800);
FORCEPROP 1 LAST COMMENT_BODY TRUE
J 2
(-7130 2830);
DISPLAY 0.872340 (-7130 2830);
PAINT PEACH (-7130 2830);
DISPLAY INVISIBLE (-7130 2830);
FORCEPROP 2 LAST CDS_LIB standard
J 0
(-7175 2925);
DISPLAY INVISIBLE (-7175 2925);
FORCEPROP 2 LAST PATH I62
J 0
(-7425 2975);
DISPLAY 0.680851 (-7425 2975);
DISPLAY INVISIBLE (-7425 2975);
FORCEADD OFFPAGE..2
R 2
(-7175 2825);
FORCEPROP 2 LAST $XR0 10 
J 0
(-7429 2825);
DISPLAY 0.638298 (-7429 2825);
PAINT MONO (-7429 2825);
FORCEPROP 2 LAST CDS_LIB standard
J 0
(-7175 2825);
DISPLAY INVISIBLE (-7175 2825);
FORCEPROP 1 LAST COMMENT_BODY TRUE
J 2
(-7130 2730);
DISPLAY 0.872340 (-7130 2730);
PAINT PEACH (-7130 2730);
DISPLAY INVISIBLE (-7130 2730);
FORCEPROP 1 LAST OFFPAGE TRUE
J 2
(-7500 2700);
DISPLAY 0.872340 (-7500 2700);
PAINT GREEN (-7500 2700);
DISPLAY INVISIBLE (-7500 2700);
FORCEPROP 2 LAST PATH I63
J 0
(-7425 2875);
DISPLAY 0.680851 (-7425 2875);
DISPLAY INVISIBLE (-7425 2875);
FORCEADD OFFPAGE..1
(-7075 1225);
FORCEPROP 2 LAST $XR0 10 
J 0
(-7296 1225);
DISPLAY 0.638298 (-7296 1225);
PAINT MONO (-7296 1225);
FORCEPROP 2 LAST CDS_LIB standard
J 0
(-7075 1225);
DISPLAY INVISIBLE (-7075 1225);
FORCEPROP 1 LAST COMMENT_BODY TRUE
J 0
(-6945 1125);
DISPLAY 1.106383 (-6945 1125);
PAINT PEACH (-6945 1125);
DISPLAY INVISIBLE (-6945 1125);
FORCEPROP 1 LAST OFFPAGE TRUE
J 0
(-6745 1095);
PAINT GREEN (-6745 1095);
DISPLAY INVISIBLE (-6745 1095);
FORCEPROP 2 LAST PATH I68
J 0
(-7275 1275);
DISPLAY 0.680851 (-7275 1275);
DISPLAY INVISIBLE (-7275 1275);
FORCEADD OFFPAGE..1
(-7075 1325);
FORCEPROP 2 LAST $XR0 29 
J 0
(-7296 1325);
DISPLAY 0.638298 (-7296 1325);
PAINT MONO (-7296 1325);
FORCEPROP 1 LAST OFFPAGE TRUE
J 0
(-6745 1195);
PAINT GREEN (-6745 1195);
DISPLAY INVISIBLE (-6745 1195);
FORCEPROP 1 LAST COMMENT_BODY TRUE
J 0
(-6945 1225);
DISPLAY 1.106383 (-6945 1225);
PAINT PEACH (-6945 1225);
DISPLAY INVISIBLE (-6945 1225);
FORCEPROP 2 LAST CDS_LIB standard
J 0
(-7075 1325);
DISPLAY INVISIBLE (-7075 1325);
FORCEPROP 2 LAST PATH I69
J 0
(-7275 1375);
DISPLAY 0.680851 (-7275 1375);
DISPLAY INVISIBLE (-7275 1375);
FORCEADD UNIVERSAL_GND..1
R 2
(-5075 5300);
FORCEPROP 3 LASTPIN (-5075 5350) SIG_NAME GND\g
J 0
(-5065 5360);
DISPLAY 0.659574 (-5065 5360);
PAINT MONO (-5065 5360);
DISPLAY INVISIBLE (-5065 5360);
FORCEPROP 2 LAST CDS_LIB logical_power
J 0
(-5075 5300);
DISPLAY INVISIBLE (-5075 5300);
FORCEPROP 1 LAST HDL_POWER GND
J 1
(-5100 5225);
DISPLAY 0.702128 (-5100 5225);
PAINT GREEN (-5100 5225);
DISPLAY INVISIBLE (-5100 5225);
FORCEPROP 1 LAST PATH I7
J 2
(-5150 5300);
DISPLAY 0.872340 (-5150 5300);
PAINT AQUA (-5150 5300);
DISPLAY INVISIBLE (-5150 5300);
FORCEADD Q_RES..1
(-6175 5550);
FORCEPROP 1 LAST MATERIAL CHIP
J 0
(-6025 5550);
DISPLAY 0.510638 (-6025 5550);
PAINT SKYBLUE (-6025 5550);
FORCEPROP 1 LAST VALUE 0
J 2
(-6075 5550);
DISPLAY 0.510638 (-6075 5550);
PAINT SKYBLUE (-6075 5550);
FORCEPROP 1 LAST TOLERANCE 5%
J 0
(-6250 5650);
DISPLAY 0.510638 (-6250 5650);
PAINT SKYBLUE (-6250 5650);
DISPLAY INVISIBLE (-6250 5650);
FORCEPROP 1 LAST WATTAGE 1/16W
J 2
(-5825 5650);
DISPLAY 0.510638 (-5825 5650);
PAINT SKYBLUE (-5825 5650);
DISPLAY INVISIBLE (-5825 5650);
FORCEPROP 1 LAST PACK_TYPE 0402LF
J 0
(-6200 5600);
DISPLAY 0.510638 (-6200 5600);
PAINT SKYBLUE (-6200 5600);
DISPLAY INVISIBLE (-6200 5600);
FORCEPROP 1 LAST PART_NUMBER CS00002JB13
J 0
(-6275 5625);
DISPLAY 0.510638 (-6275 5625);
PAINT WHITE (-6275 5625);
DISPLAY INVISIBLE (-6275 5625);
FORCEPROP 1 LAST PATH I70
J 0
(-6225 5700);
DISPLAY 0.978723 (-6225 5700);
PAINT WHITE (-6225 5700);
DISPLAY INVISIBLE (-6225 5700);
FORCEPROP 2 LAST CDS_LIB pure_quanta
J 0
(-6175 5550);
DISPLAY INVISIBLE (-6175 5550);
FORCEPROP 1 LAST LOCATION R900
J 0
(-6375 5550);
DISPLAY 0.702128 (-6375 5550);
PAINT YELLOW (-6375 5550);
FORCEPROP 1 LASTPIN (-6275 5550) $PN 1
J 0
(-6263 5562);
DISPLAY 0.787234 (-6263 5562);
PAINT MONO (-6263 5562);
FORCEPROP 1 LASTPIN (-6075 5550) $PN 2
J 0
(-6113 5562);
DISPLAY 0.787234 (-6113 5562);
PAINT MONO (-6113 5562);
FORCEPROP 0 LAST $SEC 1
J 0
(-6375 5600);
DISPLAY 0.680851 (-6375 5600);
PAINT MONO (-6375 5600);
DISPLAY INVISIBLE (-6375 5600);
FORCEPROP 0 LAST CDS_SEC 1
J 0
(-6375 5600);
DISPLAY 0.680851 (-6375 5600);
DISPLAY INVISIBLE (-6375 5600);
FORCEADD Q_RES..1
(-6300 5450);
FORCEPROP 1 LAST MATERIAL CHIP
J 0
(-6150 5450);
DISPLAY 0.510638 (-6150 5450);
PAINT SKYBLUE (-6150 5450);
FORCEPROP 1 LAST VALUE 0
J 2
(-6200 5450);
DISPLAY 0.510638 (-6200 5450);
PAINT SKYBLUE (-6200 5450);
FORCEPROP 1 LAST TOLERANCE 5%
J 0
(-6375 5550);
DISPLAY 0.510638 (-6375 5550);
PAINT SKYBLUE (-6375 5550);
DISPLAY INVISIBLE (-6375 5550);
FORCEPROP 1 LAST WATTAGE 1/16W
J 2
(-5950 5550);
DISPLAY 0.510638 (-5950 5550);
PAINT SKYBLUE (-5950 5550);
DISPLAY INVISIBLE (-5950 5550);
FORCEPROP 1 LAST PACK_TYPE 0402LF
J 0
(-6325 5500);
DISPLAY 0.510638 (-6325 5500);
PAINT SKYBLUE (-6325 5500);
DISPLAY INVISIBLE (-6325 5500);
FORCEPROP 1 LAST PART_NUMBER CS00002JB13
J 0
(-6400 5525);
DISPLAY 0.510638 (-6400 5525);
PAINT WHITE (-6400 5525);
DISPLAY INVISIBLE (-6400 5525);
FORCEPROP 1 LAST PATH I71
J 0
(-6350 5600);
DISPLAY 0.978723 (-6350 5600);
PAINT WHITE (-6350 5600);
DISPLAY INVISIBLE (-6350 5600);
FORCEPROP 2 LAST CDS_LIB pure_quanta
J 0
(-6300 5450);
DISPLAY INVISIBLE (-6300 5450);
FORCEPROP 1 LAST LOCATION R901
J 0
(-6500 5450);
DISPLAY 0.702128 (-6500 5450);
PAINT YELLOW (-6500 5450);
FORCEPROP 1 LASTPIN (-6400 5450) $PN 1
J 0
(-6388 5462);
DISPLAY 0.787234 (-6388 5462);
PAINT MONO (-6388 5462);
FORCEPROP 1 LASTPIN (-6200 5450) $PN 2
J 0
(-6238 5462);
DISPLAY 0.787234 (-6238 5462);
PAINT MONO (-6238 5462);
FORCEPROP 0 LAST $SEC 1
J 0
(-6500 5500);
DISPLAY 0.680851 (-6500 5500);
PAINT MONO (-6500 5500);
DISPLAY INVISIBLE (-6500 5500);
FORCEPROP 0 LAST CDS_SEC 1
J 0
(-6500 5500);
DISPLAY 0.680851 (-6500 5500);
DISPLAY INVISIBLE (-6500 5500);
FORCEADD Q_RES..1
(-6200 4400);
FORCEPROP 1 LAST MATERIAL CHIP
J 0
(-6050 4400);
DISPLAY 0.510638 (-6050 4400);
PAINT SKYBLUE (-6050 4400);
FORCEPROP 1 LAST VALUE 0
J 2
(-6100 4400);
DISPLAY 0.510638 (-6100 4400);
PAINT SKYBLUE (-6100 4400);
FORCEPROP 1 LAST TOLERANCE 5%
J 0
(-6275 4500);
DISPLAY 0.510638 (-6275 4500);
PAINT SKYBLUE (-6275 4500);
DISPLAY INVISIBLE (-6275 4500);
FORCEPROP 1 LAST WATTAGE 1/16W
J 2
(-5850 4500);
DISPLAY 0.510638 (-5850 4500);
PAINT SKYBLUE (-5850 4500);
DISPLAY INVISIBLE (-5850 4500);
FORCEPROP 1 LAST PACK_TYPE 0402LF
J 0
(-6225 4450);
DISPLAY 0.510638 (-6225 4450);
PAINT SKYBLUE (-6225 4450);
DISPLAY INVISIBLE (-6225 4450);
FORCEPROP 1 LAST PART_NUMBER CS00002JB13
J 0
(-6300 4475);
DISPLAY 0.510638 (-6300 4475);
PAINT WHITE (-6300 4475);
DISPLAY INVISIBLE (-6300 4475);
FORCEPROP 1 LAST PATH I72
J 0
(-6250 4550);
DISPLAY 0.978723 (-6250 4550);
PAINT WHITE (-6250 4550);
DISPLAY INVISIBLE (-6250 4550);
FORCEPROP 2 LAST CDS_LIB pure_quanta
J 0
(-6200 4400);
DISPLAY INVISIBLE (-6200 4400);
FORCEPROP 1 LAST LOCATION R902
J 0
(-6400 4400);
DISPLAY 0.702128 (-6400 4400);
PAINT YELLOW (-6400 4400);
FORCEPROP 1 LASTPIN (-6300 4400) $PN 1
J 0
(-6288 4412);
DISPLAY 0.787234 (-6288 4412);
PAINT MONO (-6288 4412);
FORCEPROP 1 LASTPIN (-6100 4400) $PN 2
J 0
(-6138 4412);
DISPLAY 0.787234 (-6138 4412);
PAINT MONO (-6138 4412);
FORCEPROP 0 LAST $SEC 1
J 0
(-6400 4450);
DISPLAY 0.680851 (-6400 4450);
PAINT MONO (-6400 4450);
DISPLAY INVISIBLE (-6400 4450);
FORCEPROP 0 LAST CDS_SEC 1
J 0
(-6400 4450);
DISPLAY 0.680851 (-6400 4450);
DISPLAY INVISIBLE (-6400 4450);
FORCEADD Q_RES..1
(-6200 4300);
FORCEPROP 1 LAST MATERIAL CHIP
J 0
(-6050 4300);
DISPLAY 0.510638 (-6050 4300);
PAINT SKYBLUE (-6050 4300);
FORCEPROP 1 LAST VALUE 0
J 2
(-6100 4300);
DISPLAY 0.510638 (-6100 4300);
PAINT SKYBLUE (-6100 4300);
FORCEPROP 1 LAST TOLERANCE 5%
J 0
(-6275 4400);
DISPLAY 0.510638 (-6275 4400);
PAINT SKYBLUE (-6275 4400);
DISPLAY INVISIBLE (-6275 4400);
FORCEPROP 1 LAST WATTAGE 1/16W
J 2
(-5850 4400);
DISPLAY 0.510638 (-5850 4400);
PAINT SKYBLUE (-5850 4400);
DISPLAY INVISIBLE (-5850 4400);
FORCEPROP 1 LAST PACK_TYPE 0402LF
J 0
(-6225 4350);
DISPLAY 0.510638 (-6225 4350);
PAINT SKYBLUE (-6225 4350);
DISPLAY INVISIBLE (-6225 4350);
FORCEPROP 1 LAST PART_NUMBER CS00002JB13
J 0
(-6300 4375);
DISPLAY 0.510638 (-6300 4375);
PAINT WHITE (-6300 4375);
DISPLAY INVISIBLE (-6300 4375);
FORCEPROP 1 LAST PATH I73
J 0
(-6250 4450);
DISPLAY 0.978723 (-6250 4450);
PAINT WHITE (-6250 4450);
DISPLAY INVISIBLE (-6250 4450);
FORCEPROP 2 LAST CDS_LIB pure_quanta
J 0
(-6200 4300);
DISPLAY INVISIBLE (-6200 4300);
FORCEPROP 1 LAST LOCATION R903
J 0
(-6400 4300);
DISPLAY 0.702128 (-6400 4300);
PAINT YELLOW (-6400 4300);
FORCEPROP 1 LASTPIN (-6300 4300) $PN 1
J 0
(-6288 4312);
DISPLAY 0.787234 (-6288 4312);
PAINT MONO (-6288 4312);
FORCEPROP 1 LASTPIN (-6100 4300) $PN 2
J 0
(-6138 4312);
DISPLAY 0.787234 (-6138 4312);
PAINT MONO (-6138 4312);
FORCEPROP 0 LAST $SEC 1
J 0
(-6400 4350);
DISPLAY 0.680851 (-6400 4350);
PAINT MONO (-6400 4350);
DISPLAY INVISIBLE (-6400 4350);
FORCEPROP 0 LAST CDS_SEC 1
J 0
(-6400 4350);
DISPLAY 0.680851 (-6400 4350);
DISPLAY INVISIBLE (-6400 4350);
FORCEADD Q_RES..1
(-6175 2825);
FORCEPROP 1 LAST PART_NUMBER CS00002JB13
J 0
(-6275 2875);
DISPLAY 0.510638 (-6275 2875);
PAINT WHITE (-6275 2875);
FORCEPROP 1 LAST TOLERANCE 5%
J 0
(-6050 2800);
DISPLAY 0.510638 (-6050 2800);
PAINT SKYBLUE (-6050 2800);
FORCEPROP 1 LAST VALUE 0
J 2
(-6025 2825);
DISPLAY 0.510638 (-6025 2825);
PAINT SKYBLUE (-6025 2825);
FORCEPROP 1 LAST MATERIAL CHIP
J 0
(-5975 2825);
DISPLAY 0.510638 (-5975 2825);
PAINT SKYBLUE (-5975 2825);
FORCEPROP 1 LAST PACK_TYPE 0402LF
J 0
(-6375 2800);
DISPLAY 0.510638 (-6375 2800);
PAINT SKYBLUE (-6375 2800);
FORCEPROP 2 LAST CDS_LIB pure_quanta
J 0
(-6175 2825);
DISPLAY INVISIBLE (-6175 2825);
FORCEPROP 1 LAST PATH I74
J 0
(-6225 2975);
DISPLAY 0.978723 (-6225 2975);
PAINT WHITE (-6225 2975);
DISPLAY INVISIBLE (-6225 2975);
FORCEPROP 1 LAST WATTAGE 1/16W
J 2
(-6000 2900);
DISPLAY 0.510638 (-6000 2900);
PAINT SKYBLUE (-6000 2900);
DISPLAY INVISIBLE (-6000 2900);
FORCEPROP 1 LAST LOCATION R544
J 0
(-6400 2825);
DISPLAY 0.702128 (-6400 2825);
PAINT YELLOW (-6400 2825);
FORCEPROP 1 LASTPIN (-6275 2825) $PN 1
J 0
(-6263 2837);
DISPLAY 0.787234 (-6263 2837);
PAINT MONO (-6263 2837);
FORCEPROP 1 LASTPIN (-6075 2825) $PN 2
J 0
(-6113 2837);
DISPLAY 0.787234 (-6113 2837);
PAINT MONO (-6113 2837);
FORCEPROP 0 LAST $SEC 1
J 0
(-6275 2875);
DISPLAY 0.680851 (-6275 2875);
PAINT MONO (-6275 2875);
DISPLAY INVISIBLE (-6275 2875);
FORCEPROP 0 LAST CDS_SEC 1
J 0
(-6275 2875);
DISPLAY 0.680851 (-6275 2875);
DISPLAY INVISIBLE (-6275 2875);
FORCEADD Q_RES..1
(-6175 2925);
FORCEPROP 1 LAST MATERIAL CHIP
J 0
(-5975 2925);
DISPLAY 0.510638 (-5975 2925);
PAINT SKYBLUE (-5975 2925);
FORCEPROP 1 LAST VALUE 0
J 2
(-6025 2925);
DISPLAY 0.510638 (-6025 2925);
PAINT SKYBLUE (-6025 2925);
FORCEPROP 1 LAST PART_NUMBER CS00002JB13
J 0
(-6275 2975);
DISPLAY 0.510638 (-6275 2975);
PAINT WHITE (-6275 2975);
FORCEPROP 1 LAST TOLERANCE 5%
J 0
(-6050 2900);
DISPLAY 0.510638 (-6050 2900);
PAINT SKYBLUE (-6050 2900);
FORCEPROP 1 LAST PACK_TYPE 0402LF
J 0
(-6375 2900);
DISPLAY 0.510638 (-6375 2900);
PAINT SKYBLUE (-6375 2900);
FORCEPROP 1 LAST WATTAGE 1/16W
J 2
(-6000 3000);
DISPLAY 0.510638 (-6000 3000);
PAINT SKYBLUE (-6000 3000);
DISPLAY INVISIBLE (-6000 3000);
FORCEPROP 1 LAST PATH I75
J 0
(-6225 3075);
DISPLAY 0.978723 (-6225 3075);
PAINT WHITE (-6225 3075);
DISPLAY INVISIBLE (-6225 3075);
FORCEPROP 2 LAST CDS_LIB pure_quanta
J 0
(-6175 2925);
DISPLAY INVISIBLE (-6175 2925);
FORCEPROP 1 LAST LOCATION R546
J 0
(-6400 2925);
DISPLAY 0.702128 (-6400 2925);
PAINT YELLOW (-6400 2925);
FORCEPROP 1 LASTPIN (-6275 2925) $PN 1
J 0
(-6263 2937);
DISPLAY 0.787234 (-6263 2937);
PAINT MONO (-6263 2937);
FORCEPROP 1 LASTPIN (-6075 2925) $PN 2
J 0
(-6113 2937);
DISPLAY 0.787234 (-6113 2937);
PAINT MONO (-6113 2937);
FORCEPROP 0 LAST $SEC 1
J 0
(-6275 2975);
DISPLAY 0.680851 (-6275 2975);
PAINT MONO (-6275 2975);
DISPLAY INVISIBLE (-6275 2975);
FORCEPROP 0 LAST CDS_SEC 1
J 0
(-6275 2975);
DISPLAY 0.680851 (-6275 2975);
DISPLAY INVISIBLE (-6275 2975);
FORCEADD Q_RES..1
(-6075 1225);
FORCEPROP 1 LAST MATERIAL CHIP
J 0
(-5875 1225);
DISPLAY 0.510638 (-5875 1225);
PAINT SKYBLUE (-5875 1225);
FORCEPROP 1 LAST PACK_TYPE 0402LF
J 0
(-6275 1200);
DISPLAY 0.510638 (-6275 1200);
PAINT SKYBLUE (-6275 1200);
FORCEPROP 1 LAST VALUE 0
J 2
(-5925 1225);
DISPLAY 0.510638 (-5925 1225);
PAINT SKYBLUE (-5925 1225);
FORCEPROP 1 LAST TOLERANCE 5%
J 0
(-5950 1200);
DISPLAY 0.510638 (-5950 1200);
PAINT SKYBLUE (-5950 1200);
FORCEPROP 1 LAST PART_NUMBER CS00002JB13
J 0
(-6175 1275);
DISPLAY 0.510638 (-6175 1275);
PAINT WHITE (-6175 1275);
FORCEPROP 1 LAST WATTAGE 1/16W
J 2
(-5900 1300);
DISPLAY 0.510638 (-5900 1300);
PAINT SKYBLUE (-5900 1300);
DISPLAY INVISIBLE (-5900 1300);
FORCEPROP 1 LAST PATH I76
J 0
(-6125 1375);
DISPLAY 0.978723 (-6125 1375);
PAINT WHITE (-6125 1375);
DISPLAY INVISIBLE (-6125 1375);
FORCEPROP 2 LAST CDS_LIB pure_quanta
J 0
(-6075 1225);
DISPLAY INVISIBLE (-6075 1225);
FORCEPROP 1 LAST LOCATION R618
J 0
(-6300 1225);
DISPLAY 0.702128 (-6300 1225);
PAINT YELLOW (-6300 1225);
FORCEPROP 1 LASTPIN (-6175 1225) $PN 1
J 0
(-6163 1237);
DISPLAY 0.787234 (-6163 1237);
PAINT MONO (-6163 1237);
FORCEPROP 1 LASTPIN (-5975 1225) $PN 2
J 0
(-6013 1237);
DISPLAY 0.787234 (-6013 1237);
PAINT MONO (-6013 1237);
FORCEPROP 0 LAST $SEC 1
J 0
(-6175 1275);
DISPLAY 0.680851 (-6175 1275);
PAINT MONO (-6175 1275);
DISPLAY INVISIBLE (-6175 1275);
FORCEPROP 0 LAST CDS_SEC 1
J 0
(-6175 1275);
DISPLAY 0.680851 (-6175 1275);
DISPLAY INVISIBLE (-6175 1275);
FORCEADD Q_RES..1
(-6075 1325);
FORCEPROP 1 LAST MATERIAL CHIP
J 0
(-5875 1325);
DISPLAY 0.510638 (-5875 1325);
PAINT SKYBLUE (-5875 1325);
FORCEPROP 1 LAST PACK_TYPE 0402LF
J 0
(-6275 1300);
DISPLAY 0.510638 (-6275 1300);
PAINT SKYBLUE (-6275 1300);
FORCEPROP 1 LAST VALUE 100
J 2
(-5925 1325);
DISPLAY 0.510638 (-5925 1325);
PAINT SKYBLUE (-5925 1325);
FORCEPROP 1 LAST TOLERANCE 1%
J 0
(-5950 1300);
DISPLAY 0.510638 (-5950 1300);
PAINT SKYBLUE (-5950 1300);
FORCEPROP 1 LAST PART_NUMBER CS11002FB07
J 0
(-6175 1375);
DISPLAY 0.510638 (-6175 1375);
PAINT WHITE (-6175 1375);
FORCEPROP 2 LAST CDS_LIB pure_quanta
J 0
(-6075 1325);
DISPLAY INVISIBLE (-6075 1325);
FORCEPROP 1 LAST PATH I77
J 0
(-6125 1475);
DISPLAY 0.978723 (-6125 1475);
PAINT WHITE (-6125 1475);
DISPLAY INVISIBLE (-6125 1475);
FORCEPROP 1 LAST WATTAGE 1/16W
J 2
(-5900 1400);
DISPLAY 0.510638 (-5900 1400);
PAINT SKYBLUE (-5900 1400);
DISPLAY INVISIBLE (-5900 1400);
FORCEPROP 1 LAST LOCATION R628
J 0
(-6300 1325);
DISPLAY 0.702128 (-6300 1325);
PAINT YELLOW (-6300 1325);
FORCEPROP 1 LASTPIN (-6175 1325) $PN 1
J 0
(-6163 1337);
DISPLAY 0.787234 (-6163 1337);
PAINT MONO (-6163 1337);
FORCEPROP 1 LASTPIN (-5975 1325) $PN 2
J 0
(-6013 1337);
DISPLAY 0.787234 (-6013 1337);
PAINT MONO (-6013 1337);
FORCEPROP 0 LAST $SEC 1
J 0
(-6175 1375);
DISPLAY 0.680851 (-6175 1375);
PAINT MONO (-6175 1375);
DISPLAY INVISIBLE (-6175 1375);
FORCEPROP 0 LAST CDS_SEC 1
J 0
(-6175 1375);
DISPLAY 0.680851 (-6175 1375);
DISPLAY INVISIBLE (-6175 1375);
FORCEADD Q_RES..1
(-2550 2225);
FORCEPROP 1 LAST VALUE 0
J 2
(-2400 2225);
DISPLAY 0.510638 (-2400 2225);
PAINT SKYBLUE (-2400 2225);
FORCEPROP 1 LAST MATERIAL CHIP
J 0
(-2350 2225);
DISPLAY 0.510638 (-2350 2225);
PAINT SKYBLUE (-2350 2225);
FORCEPROP 1 LAST TOLERANCE 5%
J 0
(-2425 2200);
DISPLAY 0.510638 (-2425 2200);
PAINT SKYBLUE (-2425 2200);
FORCEPROP 1 LAST PART_NUMBER CS00002JB13
J 0
(-2650 2275);
DISPLAY 0.510638 (-2650 2275);
PAINT WHITE (-2650 2275);
FORCEPROP 1 LAST PACK_TYPE 0402LF
J 0
(-2750 2200);
DISPLAY 0.510638 (-2750 2200);
PAINT SKYBLUE (-2750 2200);
FORCEPROP 1 LAST WATTAGE 1/16W
J 2
(-2375 2300);
DISPLAY 0.510638 (-2375 2300);
PAINT SKYBLUE (-2375 2300);
DISPLAY INVISIBLE (-2375 2300);
FORCEPROP 1 LAST PATH I78
J 0
(-2600 2375);
DISPLAY 0.978723 (-2600 2375);
PAINT WHITE (-2600 2375);
DISPLAY INVISIBLE (-2600 2375);
FORCEPROP 2 LAST CDS_LIB pure_quanta
J 0
(-2550 2225);
DISPLAY INVISIBLE (-2550 2225);
FORCEPROP 1 LAST LOCATION R629
J 0
(-2775 2225);
DISPLAY 0.702128 (-2775 2225);
PAINT YELLOW (-2775 2225);
FORCEPROP 1 LASTPIN (-2650 2225) $PN 1
J 0
(-2638 2237);
DISPLAY 0.787234 (-2638 2237);
PAINT MONO (-2638 2237);
FORCEPROP 1 LASTPIN (-2450 2225) $PN 2
J 0
(-2488 2237);
DISPLAY 0.787234 (-2488 2237);
PAINT MONO (-2488 2237);
FORCEPROP 0 LAST $SEC 1
J 0
(-2650 2275);
DISPLAY 0.680851 (-2650 2275);
PAINT MONO (-2650 2275);
DISPLAY INVISIBLE (-2650 2275);
FORCEPROP 0 LAST CDS_SEC 1
J 0
(-2650 2275);
DISPLAY 0.680851 (-2650 2275);
DISPLAY INVISIBLE (-2650 2275);
FORCEADD Q_RES..2
(-2175 2325);
FORCEPROP 1 LAST PART_NUMBER CS24702FB06
J 0
(-2135 2200);
DISPLAY 0.638298 (-2135 2200);
FORCEPROP 1 LAST WATTAGE 1/16W
J 0
(-2135 2300);
DISPLAY 0.638298 (-2135 2300);
FORCEPROP 1 LAST TOLERANCE 1%
J 0
(-2130 2350);
DISPLAY 0.638298 (-2130 2350);
FORCEPROP 1 LAST VALUE 4.7K
J 0
(-2130 2400);
DISPLAY 0.638298 (-2130 2400);
FORCEPROP 1 LAST PACK_TYPE 0402LF
J 0
(-2135 2150);
DISPLAY 0.638298 (-2135 2150);
FORCEPROP 1 LAST MATERIAL CHIP
J 0
(-2135 2250);
DISPLAY 0.638298 (-2135 2250);
FORCEPROP 1 LAST PATH I79
J 0
(-2125 2500);
DISPLAY 0.978723 (-2125 2500);
PAINT WHITE (-2125 2500);
DISPLAY INVISIBLE (-2125 2500);
FORCEPROP 2 LAST CDS_LIB pure_quanta
J 0
(-2175 2325);
DISPLAY INVISIBLE (-2175 2325);
FORCEPROP 1 LAST LOCATION R630
J 0
(-2130 2450);
DISPLAY 0.638298 (-2130 2450);
FORCEPROP 1 LASTPIN (-2175 2425) $PN 1
J 0
(-2170 2387);
DISPLAY 0.787234 (-2170 2387);
PAINT MONO (-2170 2387);
FORCEPROP 1 LASTPIN (-2175 2225) $PN 2
J 0
(-2170 2235);
DISPLAY 0.787234 (-2170 2235);
PAINT MONO (-2170 2235);
FORCEPROP 0 LAST $SEC 1
J 0
(-2125 2500);
DISPLAY 0.680851 (-2125 2500);
PAINT MONO (-2125 2500);
DISPLAY INVISIBLE (-2125 2500);
FORCEPROP 0 LAST CDS_SEC 1
J 0
(-2125 2500);
DISPLAY 0.680851 (-2125 2500);
DISPLAY INVISIBLE (-2125 2500);
FORCEADD Q_RES..2
(-2000 5825);
FORCEPROP 1 LAST TOLERANCE 1%
J 0
(-1955 5850);
DISPLAY 0.510638 (-1955 5850);
PAINT SKYBLUE (-1955 5850);
FORCEPROP 1 LAST PACK_TYPE 0402LF
J 0
(-1960 5650);
DISPLAY 0.510638 (-1960 5650);
PAINT SKYBLUE (-1960 5650);
FORCEPROP 1 LAST MATERIAL CHIP
J 0
(-1960 5750);
DISPLAY 0.510638 (-1960 5750);
PAINT SKYBLUE (-1960 5750);
FORCEPROP 1 LAST WATTAGE 1/16W
J 0
(-1960 5800);
DISPLAY 0.510638 (-1960 5800);
PAINT SKYBLUE (-1960 5800);
FORCEPROP 1 LAST VALUE 100K
J 0
(-1955 5900);
DISPLAY 0.510638 (-1955 5900);
PAINT SKYBLUE (-1955 5900);
FORCEPROP 1 LAST PART_NUMBER CS41002FB09
J 0
(-1960 5700);
DISPLAY 0.510638 (-1960 5700);
PAINT WHITE (-1960 5700);
FORCEPROP 1 LAST PATH I80
J 0
(-1950 6000);
DISPLAY 0.978723 (-1950 6000);
PAINT WHITE (-1950 6000);
DISPLAY INVISIBLE (-1950 6000);
FORCEPROP 2 LAST CDS_LIB pure_quanta
J 0
(-2000 5825);
DISPLAY INVISIBLE (-2000 5825);
FORCEPROP 1 LAST $LOCATION R396
J 0
(-1955 5950);
DISPLAY 0.702128 (-1955 5950);
PAINT YELLOW (-1955 5950);
FORCEPROP 1 LASTPIN (-2000 5925) $PN 1
J 0
(-1995 5887);
DISPLAY 0.787234 (-1995 5887);
PAINT MONO (-1995 5887);
FORCEPROP 1 LASTPIN (-2000 5725) $PN 2
J 0
(-1995 5735);
DISPLAY 0.787234 (-1995 5735);
PAINT MONO (-1995 5735);
FORCEPROP 0 LAST CDS_LOCATION R396
J 0
(-1950 6000);
DISPLAY 0.680851 (-1950 6000);
DISPLAY INVISIBLE (-1950 6000);
FORCEPROP 0 LAST $SEC 1
J 0
(-1950 6000);
DISPLAY 0.680851 (-1950 6000);
PAINT MONO (-1950 6000);
DISPLAY INVISIBLE (-1950 6000);
FORCEPROP 0 LAST CDS_SEC 1
J 0
(-1950 6000);
DISPLAY 0.680851 (-1950 6000);
DISPLAY INVISIBLE (-1950 6000);
FORCEADD UNIVERSAL_POWER..1
(-2000 6125);
FORCEPROP 3 LASTPIN (-2000 6075) SIG_NAME P3V3_AUX\g
J 0
(-1990 6085);
DISPLAY 0.659574 (-1990 6085);
PAINT MONO (-1990 6085);
DISPLAY INVISIBLE (-1990 6085);
FORCEPROP 1 LAST HDL_POWER P3V3_AUX
J 1
(-2000 6175);
DISPLAY 0.702128 (-2000 6175);
PAINT PEACH (-2000 6175);
FORCEPROP 1 LAST PATH I81
J 0
(-1950 6150);
DISPLAY 0.872340 (-1950 6150);
PAINT AQUA (-1950 6150);
DISPLAY INVISIBLE (-1950 6150);
FORCEPROP 2 LAST CDS_LIB logical_power
J 0
(-2000 6125);
DISPLAY INVISIBLE (-2000 6125);
FORCEADD UNIVERSAL_GND..1
R 2
(-5050 4125);
FORCEPROP 3 LASTPIN (-5050 4175) SIG_NAME GND\g
J 0
(-5040 4185);
DISPLAY 0.659574 (-5040 4185);
PAINT MONO (-5040 4185);
DISPLAY INVISIBLE (-5040 4185);
FORCEPROP 1 LAST HDL_POWER GND
J 1
(-5075 4050);
DISPLAY 0.702128 (-5075 4050);
PAINT GREEN (-5075 4050);
DISPLAY INVISIBLE (-5075 4050);
FORCEPROP 2 LAST CDS_LIB logical_power
J 0
(-5050 4125);
DISPLAY INVISIBLE (-5050 4125);
FORCEPROP 1 LAST PATH I9
J 2
(-5125 4125);
DISPLAY 0.872340 (-5125 4125);
PAINT AQUA (-5125 4125);
DISPLAY INVISIBLE (-5125 4125);
FORCEADD QUANTA_TITLE_BLOCK_C..1
(0 0);
FORCEPROP 0 LAST CDS_CON_LAST_MODIFIED Fri Aug 25 17:25:43 2023
J 0
(-1885 15);
DISPLAY INVISIBLE (-1885 15);
FORCEPROP 2 LAST Q_DEPT 
J 1
(-3763 49);
DISPLAY 1.957447 (-3763 49);
PAINT GREEN (-3763 49);
FORCEPROP 1 LAST CUSTOM_TXT_CDS <CON_LAST_MODIFIED>
J 0
(-1885 15);
DISPLAY 0.978723 (-1885 15);
FORCEPROP 2 LAST CUSTOM_TXT_CDS <XR_PAGE_TITLE>
J 0
(-7890 5250);
DISPLAY 0.638298 (-7890 5250);
PAINT PINK (-7890 5250);
DISPLAY INVISIBLE (-7890 5250);
FORCEPROP 1 LAST CUSTOM_TXT_CDS <NAME_2>
J 0
(-3175 50);
FORCEPROP 1 LAST CUSTOM_TXT_CDS <NAME_1>
J 0
(-3175 175);
FORCEPROP 1 LAST CUSTOM_TXT_CDS <Q_NUMBER>
J 0
(-1403 103);
DISPLAY 1.212766 (-1403 103);
FORCEPROP 1 LAST CUSTOM_TXT_CDS <Q_PROJ>
J 0
(-2382 102);
DISPLAY 1.212766 (-2382 102);
FORCEPROP 1 LAST CUSTOM_TXT_CDS <Q_REV>
J 0
(-184 103);
DISPLAY 1.212766 (-184 103);
FORCEPROP 1 LAST CUSTOM_TXT_CDS <CON_PAGE_NUM> OF <CON_TOTAL_PAGES>
J 0
(-446 18);
DISPLAY 0.978723 (-446 18);
FORCEPROP 1 LAST Q_TITLE BMC DEBUG PORT 2/2
J 0
(-9366 26);
DISPLAY 2.446809 (-9366 26);
PAINT GREEN (-9366 26);
FORCEPROP 2 LAST PAGE_BORDER TRUE
J 0
(-7890 5250);
DISPLAY 0.638298 (-7890 5250);
PAINT PINK (-7890 5250);
DISPLAY INVISIBLE (-7890 5250);
FORCEPROP 2 LAST CDS_LIB pure_quanta
J 0
(0 0);
DISPLAY INVISIBLE (0 0);
FORCEPROP 1 LAST COMMENT_BODY TRUE
J 0
(12 -13);
DISPLAY 0.978723 (12 -13);
PAINT GREEN (12 -13);
DISPLAY INVISIBLE (12 -13);
FORCEPROP 1 LAST CDS_LMAN_SYM_OUTLINE -9475,6775,100,-125
J 0
(0 0);
DISPLAY 0.468085 (0 0);
PAINT GREEN (0 0);
DISPLAY INVISIBLE (0 0);
FORCEPROP 2 LAST CDS_XR_PAGE_TITLE CR-31 : @SCM_LIB.SCM(SCH_1):PAGE31
J 0
(-7890 5250);
DISPLAY 0.638298 (-7890 5250);
PAINT PINK (-7890 5250);
DISPLAY INVISIBLE (-7890 5250);
FORCEADD DNS..2
(-1475 2025);
PAINT RED (-1475 2025);
FORCEPROP 1 LAST COMMENT_BODY TRUE
R 1
J 0
(-1400 1800);
DISPLAY 0.872340 (-1400 1800);
PAINT PEACH (-1400 1800);
DISPLAY INVISIBLE (-1400 1800);
FORCEPROP 2 LAST CDS_LIB mstr_misc
J 0
(-1475 2025);
DISPLAY INVISIBLE (-1475 2025);
WIRE 16 -1 (-2000 6075)(-2000 5925);
WIRE 16 -1 (-4150 5050)(-4150 5000);
WIRE 16 -1 (-4125 6250)(-4125 6200);
WIRE 16 -1 (-5900 6275)(-5900 6150);
WIRE 16 -1 (-4125 3575)(-4125 3525);
WIRE 16 -1 (-2175 2425)(-2175 2500);
WIRE 16 -1 (-4025 1975)(-4025 1925);
WIRE 16 -1 (-5075 5500)(-5075 5350);
WIRE 16 -1 (-4950 5500)(-5075 5500);
WIRE 16 -1 (-2100 1975)(-2100 1800);
WIRE 16 -1 (-1650 1975)(-2100 1975);
WIRE 16 -1 (-4925 1275)(-4925 1100);
WIRE 16 -1 (-4800 1275)(-4925 1275);
WIRE 16 -1 (-4125 5875)(-4125 5925);
WIRE 16 -1 (-4150 4675)(-4150 4725);
WIRE 16 -1 (-5050 4350)(-5050 4175);
WIRE 16 -1 (-4925 4350)(-5050 4350);
WIRE 16 -1 (-5025 2875)(-5025 2700);
WIRE 16 -1 (-4900 2875)(-5025 2875);
WIRE 16 -1 (-4125 3200)(-4125 3250);
WIRE 16 -1 (-4025 1600)(-4025 1650);
WIRE 16 273 (-7725 975)(-350 975);
WIRE 16 3135 (-6225 1300)(-6225 1450);
WIRE 16 3135 (-6225 1300)(-5900 1300);
WIRE 16 3135 (-5900 1450)(-6225 1450);
WIRE 16 3135 (-5900 1450)(-5900 1300);
WIRE 16 -1 (-5975 1325)(-4800 1325);
FORCEPROP 0 LAST SIG_NAME SPA_SIN_SW_DBG_R
J 0
(-5735 1335);
DISPLAY 0.851064 (-5735 1335);
WIRE 16 -1 (-5975 1225)(-4800 1225);
FORCEPROP 0 LAST SIG_NAME UART_SYS_DBG_RX_R
J 0
(-5735 1235);
DISPLAY 0.851064 (-5735 1235);
WIRE 16 -1 (-7025 1225)(-6175 1225);
FORCEPROP 0 LAST SIG_NAME UART_SYS_DBG_RX
J 0
(-7035 1235);
DISPLAY 0.851064 (-7035 1235);
WIRE 16 -1 (-7025 1325)(-6175 1325);
FORCEPROP 0 LAST SIG_NAME SPA_SIN_SW_DBG
J 0
(-7035 1335);
DISPLAY 0.851064 (-7035 1335);
WIRE 16 273 (-7750 1000)(-7750 3925);
WIRE 16 273 (-7750 3925)(-375 3925);
WIRE 16 -1 (-2650 2225)(-3425 2225);
FORCEPROP 0 LAST SIG_NAME BMC_CPLD_GPIO_2
J 0
(-3435 2235);
DISPLAY 0.851064 (-3435 2235);
WIRE 16 -1 (-3450 2025)(-2250 2025);
FORCEPROP 0 LAST SIG_NAME FM_DBG_SW_N
J 0
(-3435 2035);
DISPLAY 0.851064 (-3435 2035);
WIRE 16 -1 (-1650 2025)(-2250 2025);
WIRE 16 -1 (-2250 2025)(-2250 2225);
WIRE 16 -1 (-2450 2225)(-2250 2225);
WIRE 16 -1 (-2175 2225)(-2175 2075);
WIRE 16 -1 (-2175 2075)(-1650 2075);
FORCEPROP 2 LAST SIG_NAME PU_J13_P1
J 0
(-2125 2085);
DISPLAY 0.851064 (-2125 2085);
WIRE 16 -1 (-4025 2875)(-4300 2875);
WIRE 16 -1 (-4125 3525)(-4125 3450);
WIRE 16 -1 (-4025 3525)(-4025 2875);
WIRE 16 -1 (-4025 3525)(-4125 3525);
WIRE 16 -1 (-3975 5500)(-4350 5500);
WIRE 16 -1 (-4125 6200)(-4125 6125);
WIRE 16 -1 (-3975 6200)(-3975 5500);
WIRE 16 -1 (-3975 6200)(-4125 6200);
WIRE 16 -1 (-2750 4400)(-4325 4400);
FORCEPROP 0 LAST SIG_NAME FM_BIC_DEBUG_SW_N
J 0
(-3585 4410);
DISPLAY 0.851064 (-3585 4410);
WIRE 16 -1 (-4350 5450)(-2000 5450);
FORCEPROP 0 LAST SIG_NAME UART_BIC_GF_RXD
J 0
(-3585 5460);
DISPLAY 0.851064 (-3585 5460);
WIRE 16 -1 (-2000 5450)(-1425 5450);
WIRE 16 -1 (-2000 5725)(-2000 5450);
WIRE 16 -1 (-2750 5550)(-4350 5550);
FORCEPROP 0 LAST SIG_NAME FM_BIC_DEBUG_SW_N
J 0
(-3585 5560);
DISPLAY 0.851064 (-3585 5560);
WIRE 16 -1 (-4325 4300)(-2750 4300);
FORCEPROP 0 LAST SIG_NAME UART_BIC_GF_TXD
J 0
(-3585 4310);
DISPLAY 0.851064 (-3585 4310);
WIRE 16 273 (-350 1050)(-350 3900);
WIRE 16 -1 (-4300 2825)(-2725 2825);
FORCEPROP 0 LAST SIG_NAME SPA_SOUT_SW_BUF_R
J 0
(-3585 2835);
DISPLAY 0.851064 (-3585 2835);
WIRE 16 -1 (-2725 2925)(-4300 2925);
FORCEPROP 0 LAST SIG_NAME FM_DBG_SW_N
J 0
(-3585 2935);
DISPLAY 0.851064 (-3585 2935);
WIRE 16 3135 (-2075 5575)(-1650 5575);
WIRE 16 3135 (-2075 6050)(-2075 5575);
WIRE 16 3135 (-1650 5575)(-1650 6050);
WIRE 16 3135 (-1650 6050)(-2075 6050);
WIRE 16 -1 (-4025 1925)(-4025 1850);
WIRE 16 -1 (-3925 1275)(-4200 1275);
WIRE 16 -1 (-3925 1925)(-4025 1925);
WIRE 16 -1 (-3925 1925)(-3925 1275);
WIRE 16 -1 (-4050 4350)(-4325 4350);
WIRE 16 -1 (-4150 5000)(-4150 4925);
WIRE 16 -1 (-4050 5000)(-4050 4350);
WIRE 16 -1 (-4050 5000)(-4150 5000);
WIRE 16 -1 (-6100 4300)(-4925 4300);
FORCEPROP 0 LAST SIG_NAME UART_6_BMC_TXD_R
J 0
(-5785 4310);
DISPLAY 0.851064 (-5785 4310);
WIRE 16 -1 (-6075 2925)(-4900 2925);
FORCEPROP 0 LAST SIG_NAME SPA_SOUT_SW_DBG_R
J 0
(-5835 2935);
DISPLAY 0.851064 (-5835 2935);
WIRE 16 -1 (-6075 2825)(-4900 2825);
FORCEPROP 0 LAST SIG_NAME UART_SYS_DBG_TX_R
J 0
(-5835 2835);
DISPLAY 0.851064 (-5835 2835);
WIRE 16 -1 (-7125 2925)(-6275 2925);
FORCEPROP 0 LAST SIG_NAME SPA_SOUT_SW_DBG
J 0
(-7110 2935);
DISPLAY 0.851064 (-7110 2935);
WIRE 16 -1 (-7125 2825)(-6275 2825);
FORCEPROP 0 LAST SIG_NAME UART_SYS_DBG_TX
J 0
(-7110 2835);
DISPLAY 0.851064 (-7110 2835);
WIRE 16 -1 (-7150 4400)(-6300 4400);
FORCEPROP 0 LAST SIG_NAME UART_BIC_DBG_RX
J 0
(-7160 4410);
DISPLAY 0.851064 (-7160 4410);
WIRE 16 -1 (-7150 4300)(-6300 4300);
FORCEPROP 0 LAST SIG_NAME UART_6_BMC_TXD
J 0
(-7160 4310);
DISPLAY 0.851064 (-7160 4310);
WIRE 16 -1 (-6100 4400)(-4925 4400);
FORCEPROP 0 LAST SIG_NAME UART_BIC_DBG_RX_R
J 0
(-5785 4410);
DISPLAY 0.851064 (-5785 4410);
WIRE 16 -1 (-7175 5550)(-6275 5550);
FORCEPROP 0 LAST SIG_NAME UART_BIC_DBG_TX
J 0
(-7110 5560);
DISPLAY 0.851064 (-7110 5560);
WIRE 16 -1 (-6200 5450)(-5900 5450);
WIRE 16 -1 (-5900 5450)(-4950 5450);
FORCEPROP 0 LAST SIG_NAME UART_6_BMC_RXD_R
J 0
(-5810 5460);
DISPLAY 0.851064 (-5810 5460);
WIRE 16 -1 (-5900 5950)(-5900 5450);
WIRE 16 -1 (-6075 5550)(-4950 5550);
FORCEPROP 0 LAST SIG_NAME UART_BIC_DBG_TX_R
J 0
(-5810 5560);
DISPLAY 0.851064 (-5810 5560);
WIRE 16 -1 (-7175 5450)(-6400 5450);
FORCEPROP 0 LAST SIG_NAME UART_6_BMC_RXD
J 0
(-7110 5460);
DISPLAY 0.851064 (-7110 5460);
WIRE 16 -1 (-2625 1325)(-4200 1325);
FORCEPROP 0 LAST SIG_NAME FM_DBG_SW_N
J 0
(-3610 1335);
DISPLAY 0.851064 (-3610 1335);
WIRE 16 -1 (-4200 1225)(-2625 1225);
FORCEPROP 0 LAST SIG_NAME SPA_SIN_SW_BUF_R
J 0
(-3610 1235);
DISPLAY 0.851064 (-3610 1235);
DOT 1 (-2000 5450);
DOT 1 (-4150 5000);
DOT 1 (-2250 2025);
DOT 1 (-4125 3525);
DOT 1 (-5900 5450);
DOT 1 (-4125 6200);
DOT 1 (-4025 1925);
FORCENOTE
ADD DBG CARD OR SYS DEBUD SELECTION
(-7775 3950) 0;
DISPLAY LEFT (-7775 3950);
DISPLAY 1.021277 (-7775 3950);
FORCENOTE
NOTE: BIC SWITCH UART,B0 IS BMC,B1 IS DEBUG CARD
(-7225 5750) 0;
DISPLAY LEFT (-7225 5750);
DISPLAY 1.021277 (-7225 5750);
FORCENOTE
ADD PU_20220804
(-1850 6075) 0;
DISPLAY LEFT (-1850 6075);
DISPLAY 1.595745 (-1850 6075);
PAINT WHITE (-1850 6075);
FORCENOTE
NOTE: BIC SWITCH UART,B0 IS BMC,B1 IS DEBUG CARD
(-7225 4600) 0;
DISPLAY LEFT (-7225 4600);
DISPLAY 1.021277 (-7225 4600);
FORCENOTE
NOTE: RESERVED SWITCH UART TO SYS,B1(DEFAULT)
(-7300 3100) 0;
DISPLAY LEFT (-7300 3100);
DISPLAY 1.021277 (-7300 3100);
FORCENOTE
R628 CHANGE FROM 0 TO 100_20230314 
(-6800 1475) 0;
DISPLAY LEFT (-6800 1475);
DISPLAY 1.021277 (-6800 1475);
PAINT WHITE (-6800 1475);
FORCENOTE
NOTE: RESERVED SWITCH UART TO SYS,B1(DEFAULT)
(-7175 1550) 0;
DISPLAY LEFT (-7175 1550);
DISPLAY 1.021277 (-7175 1550);
QUIT
